FILE_TYPE = MACRO_DRAWING;
SET COLOR_WIRE YELLOW;
SET COLOR_PROP ORANGE;
SET COLOR_DOT WHITE;
SET COLOR_ARC YELLOW;
SET COLOR_BODY GREEN;
SET COLOR_NOTE PURPLE;
SET PROP_DISPLAY VALUE;
SET PAGE_NUMBER P90;
FORCEADD UNIVERSAL_GND..1
(-1425 -350);
FORCEPROP 3 LASTPIN (-1425 -300) SIG_NAME GND\g
J 0
(-1415 -290);
DISPLAY 0.659574 (-1415 -290);
PAINT MONO (-1415 -290);
DISPLAY INVISIBLE (-1415 -290);
FORCEPROP 2 LAST CDS_LIB logical_power
J 0
(-1425 -350);
PAINT MONO (-1425 -350);
DISPLAY INVISIBLE (-1425 -350);
FORCEPROP 1 LAST HDL_POWER GND
J 1
(-1400 -425);
DISPLAY 0.872340 (-1400 -425);
PAINT GREEN (-1400 -425);
DISPLAY INVISIBLE (-1400 -425);
FORCEPROP 1 LAST PATH I1
J 0
(-1350 -350);
DISPLAY 0.872340 (-1350 -350);
PAINT AQUA (-1350 -350);
DISPLAY INVISIBLE (-1350 -350);
FORCEADD OFFPAGE..1
(-2575 1675);
FORCEPROP 2 LAST $XR1 91 
J 0
(-2886 1675);
DISPLAY 0.638298 (-2886 1675);
PAINT MONO (-2886 1675);
FORCEPROP 2 LAST $XR0 24 
J 0
(-2796 1675);
DISPLAY 0.638298 (-2796 1675);
PAINT MONO (-2796 1675);
FORCEPROP 2 LAST CDS_LIB standard
J 0
(-2575 1675);
PAINT MONO (-2575 1675);
DISPLAY INVISIBLE (-2575 1675);
FORCEPROP 1 LAST OFFPAGE TRUE
J 0
(-2250 1550);
DISPLAY 0.872340 (-2250 1550);
DISPLAY INVISIBLE (-2250 1550);
FORCEPROP 1 LAST COMMENT_BODY TRUE
J 0
(-2450 1575);
DISPLAY 0.872340 (-2450 1575);
PAINT GREEN (-2450 1575);
DISPLAY INVISIBLE (-2450 1575);
FORCEPROP 2 LAST PATH I10
J 0
(-2525 1750);
DISPLAY 1.021277 (-2525 1750);
DISPLAY INVISIBLE (-2525 1750);
FORCEADD TAP..1
(0 3375);
FORCEPROP 3 LASTPIN (-50 3375) SIG_NAME M_E_CPU0_SA_DQ<18>
J 0
(-40 3385);
DISPLAY 0.659574 (-40 3385);
PAINT MONO (-40 3385);
DISPLAY INVISIBLE (-40 3385);
FORCEPROP 1 LASTPIN (-50 3375) BN 18
J 0
(-62 3383);
DISPLAY 0.680851 (-62 3383);
PAINT GREEN (-62 3383);
FORCEPROP 2 LAST CDS_LIB standard
J 0
(0 3375);
PAINT MONO (0 3375);
DISPLAY INVISIBLE (0 3375);
FORCEPROP 1 LAST BODY_TYPE PLUMBING
J 0
(0 3425);
DISPLAY 0.872340 (0 3425);
PAINT GREEN (0 3425);
DISPLAY INVISIBLE (0 3425);
FORCEPROP 1 LAST HDL_TAP TRUE
J 0
(325 3250);
DISPLAY 0.872340 (325 3250);
DISPLAY INVISIBLE (325 3250);
FORCEPROP 1 LAST PATH I100
J 0
(-2 3375);
DISPLAY 0.872340 (-2 3375);
PAINT GREEN (-2 3375);
DISPLAY INVISIBLE (-2 3375);
FORCEADD TAP..1
(0 3325);
FORCEPROP 3 LASTPIN (-50 3325) SIG_NAME M_E_CPU0_SA_DQ<17>
J 0
(-40 3335);
DISPLAY 0.659574 (-40 3335);
PAINT MONO (-40 3335);
DISPLAY INVISIBLE (-40 3335);
FORCEPROP 1 LASTPIN (-50 3325) BN 17
J 0
(-62 3333);
DISPLAY 0.680851 (-62 3333);
PAINT GREEN (-62 3333);
FORCEPROP 2 LAST CDS_LIB standard
J 0
(0 3325);
PAINT MONO (0 3325);
DISPLAY INVISIBLE (0 3325);
FORCEPROP 1 LAST BODY_TYPE PLUMBING
J 0
(0 3375);
DISPLAY 0.872340 (0 3375);
PAINT GREEN (0 3375);
DISPLAY INVISIBLE (0 3375);
FORCEPROP 1 LAST HDL_TAP TRUE
J 0
(325 3200);
DISPLAY 0.872340 (325 3200);
DISPLAY INVISIBLE (325 3200);
FORCEPROP 1 LAST PATH I101
J 0
(-2 3325);
DISPLAY 0.872340 (-2 3325);
PAINT GREEN (-2 3325);
DISPLAY INVISIBLE (-2 3325);
FORCEADD TAP..1
(0 3475);
FORCEPROP 3 LASTPIN (-50 3475) SIG_NAME M_E_CPU0_SA_DQ<20>
J 0
(-40 3485);
DISPLAY 0.659574 (-40 3485);
PAINT MONO (-40 3485);
DISPLAY INVISIBLE (-40 3485);
FORCEPROP 1 LASTPIN (-50 3475) BN 20
J 0
(-62 3483);
DISPLAY 0.680851 (-62 3483);
PAINT GREEN (-62 3483);
FORCEPROP 2 LAST CDS_LIB standard
J 0
(0 3475);
PAINT MONO (0 3475);
DISPLAY INVISIBLE (0 3475);
FORCEPROP 1 LAST BODY_TYPE PLUMBING
J 0
(0 3525);
DISPLAY 0.872340 (0 3525);
PAINT GREEN (0 3525);
DISPLAY INVISIBLE (0 3525);
FORCEPROP 1 LAST HDL_TAP TRUE
J 0
(325 3350);
DISPLAY 0.872340 (325 3350);
DISPLAY INVISIBLE (325 3350);
FORCEPROP 1 LAST PATH I102
J 0
(-2 3475);
DISPLAY 0.872340 (-2 3475);
PAINT GREEN (-2 3475);
DISPLAY INVISIBLE (-2 3475);
FORCEADD TAP..1
(0 3525);
FORCEPROP 3 LASTPIN (-50 3525) SIG_NAME M_E_CPU0_SA_DQ<21>
J 0
(-40 3535);
DISPLAY 0.659574 (-40 3535);
PAINT MONO (-40 3535);
DISPLAY INVISIBLE (-40 3535);
FORCEPROP 1 LASTPIN (-50 3525) BN 21
J 0
(-62 3533);
DISPLAY 0.680851 (-62 3533);
PAINT GREEN (-62 3533);
FORCEPROP 2 LAST CDS_LIB standard
J 0
(0 3525);
PAINT MONO (0 3525);
DISPLAY INVISIBLE (0 3525);
FORCEPROP 1 LAST BODY_TYPE PLUMBING
J 0
(0 3575);
DISPLAY 0.872340 (0 3575);
PAINT GREEN (0 3575);
DISPLAY INVISIBLE (0 3575);
FORCEPROP 1 LAST HDL_TAP TRUE
J 0
(325 3400);
DISPLAY 0.872340 (325 3400);
DISPLAY INVISIBLE (325 3400);
FORCEPROP 1 LAST PATH I103
J 0
(-2 3525);
DISPLAY 0.872340 (-2 3525);
PAINT GREEN (-2 3525);
DISPLAY INVISIBLE (-2 3525);
FORCEADD TAP..1
(0 3575);
FORCEPROP 3 LASTPIN (-50 3575) SIG_NAME M_E_CPU0_SA_DQ<22>
J 0
(-40 3585);
DISPLAY 0.659574 (-40 3585);
PAINT MONO (-40 3585);
DISPLAY INVISIBLE (-40 3585);
FORCEPROP 1 LASTPIN (-50 3575) BN 22
J 0
(-62 3583);
DISPLAY 0.680851 (-62 3583);
PAINT GREEN (-62 3583);
FORCEPROP 2 LAST CDS_LIB standard
J 0
(0 3575);
DISPLAY INVISIBLE (0 3575);
FORCEPROP 1 LAST BODY_TYPE PLUMBING
J 0
(0 3625);
DISPLAY 0.872340 (0 3625);
PAINT GREEN (0 3625);
DISPLAY INVISIBLE (0 3625);
FORCEPROP 1 LAST HDL_TAP TRUE
J 0
(325 3450);
DISPLAY 0.872340 (325 3450);
DISPLAY INVISIBLE (325 3450);
FORCEPROP 1 LAST PATH I104
J 0
(-2 3575);
DISPLAY 0.872340 (-2 3575);
PAINT GREEN (-2 3575);
DISPLAY INVISIBLE (-2 3575);
FORCEADD TAP..1
(0 3625);
FORCEPROP 3 LASTPIN (-50 3625) SIG_NAME M_E_CPU0_SA_DQ<23>
J 0
(-40 3635);
DISPLAY 0.659574 (-40 3635);
PAINT MONO (-40 3635);
DISPLAY INVISIBLE (-40 3635);
FORCEPROP 1 LASTPIN (-50 3625) BN 23
J 0
(-62 3633);
DISPLAY 0.680851 (-62 3633);
PAINT GREEN (-62 3633);
FORCEPROP 2 LAST CDS_LIB standard
J 0
(0 3625);
DISPLAY INVISIBLE (0 3625);
FORCEPROP 1 LAST BODY_TYPE PLUMBING
J 0
(0 3675);
DISPLAY 0.872340 (0 3675);
PAINT GREEN (0 3675);
DISPLAY INVISIBLE (0 3675);
FORCEPROP 1 LAST HDL_TAP TRUE
J 0
(325 3500);
DISPLAY 0.872340 (325 3500);
DISPLAY INVISIBLE (325 3500);
FORCEPROP 1 LAST PATH I105
J 0
(-2 3625);
DISPLAY 0.872340 (-2 3625);
PAINT GREEN (-2 3625);
DISPLAY INVISIBLE (-2 3625);
FORCEADD TAP..1
(0 3675);
FORCEPROP 3 LASTPIN (-50 3675) SIG_NAME M_E_CPU0_SA_DQ<24>
J 0
(-40 3685);
DISPLAY 0.659574 (-40 3685);
PAINT MONO (-40 3685);
DISPLAY INVISIBLE (-40 3685);
FORCEPROP 1 LASTPIN (-50 3675) BN 24
J 0
(-62 3683);
DISPLAY 0.680851 (-62 3683);
PAINT GREEN (-62 3683);
FORCEPROP 2 LAST CDS_LIB standard
J 0
(0 3675);
DISPLAY INVISIBLE (0 3675);
FORCEPROP 1 LAST BODY_TYPE PLUMBING
J 0
(0 3725);
DISPLAY 0.872340 (0 3725);
PAINT GREEN (0 3725);
DISPLAY INVISIBLE (0 3725);
FORCEPROP 1 LAST HDL_TAP TRUE
J 0
(325 3550);
DISPLAY 0.872340 (325 3550);
DISPLAY INVISIBLE (325 3550);
FORCEPROP 1 LAST PATH I106
J 0
(-2 3675);
DISPLAY 0.872340 (-2 3675);
PAINT GREEN (-2 3675);
DISPLAY INVISIBLE (-2 3675);
FORCEADD TAP..1
(0 3725);
FORCEPROP 3 LASTPIN (-50 3725) SIG_NAME M_E_CPU0_SA_DQ<25>
J 0
(-40 3735);
DISPLAY 0.659574 (-40 3735);
PAINT MONO (-40 3735);
DISPLAY INVISIBLE (-40 3735);
FORCEPROP 1 LASTPIN (-50 3725) BN 25
J 0
(-62 3733);
DISPLAY 0.680851 (-62 3733);
PAINT GREEN (-62 3733);
FORCEPROP 2 LAST CDS_LIB standard
J 0
(0 3725);
DISPLAY INVISIBLE (0 3725);
FORCEPROP 1 LAST BODY_TYPE PLUMBING
J 0
(0 3775);
DISPLAY 0.872340 (0 3775);
PAINT GREEN (0 3775);
DISPLAY INVISIBLE (0 3775);
FORCEPROP 1 LAST HDL_TAP TRUE
J 0
(325 3600);
DISPLAY 0.872340 (325 3600);
DISPLAY INVISIBLE (325 3600);
FORCEPROP 1 LAST PATH I107
J 0
(-2 3725);
DISPLAY 0.872340 (-2 3725);
PAINT GREEN (-2 3725);
DISPLAY INVISIBLE (-2 3725);
FORCEADD TAP..1
(0 3775);
FORCEPROP 3 LASTPIN (-50 3775) SIG_NAME M_E_CPU0_SA_DQ<26>
J 0
(-40 3785);
DISPLAY 0.659574 (-40 3785);
PAINT MONO (-40 3785);
DISPLAY INVISIBLE (-40 3785);
FORCEPROP 1 LASTPIN (-50 3775) BN 26
J 0
(-62 3783);
DISPLAY 0.680851 (-62 3783);
PAINT GREEN (-62 3783);
FORCEPROP 2 LAST CDS_LIB standard
J 0
(0 3775);
DISPLAY INVISIBLE (0 3775);
FORCEPROP 1 LAST BODY_TYPE PLUMBING
J 0
(0 3825);
DISPLAY 0.872340 (0 3825);
PAINT GREEN (0 3825);
DISPLAY INVISIBLE (0 3825);
FORCEPROP 1 LAST HDL_TAP TRUE
J 0
(325 3650);
DISPLAY 0.872340 (325 3650);
DISPLAY INVISIBLE (325 3650);
FORCEPROP 1 LAST PATH I108
J 0
(-2 3775);
DISPLAY 0.872340 (-2 3775);
PAINT GREEN (-2 3775);
DISPLAY INVISIBLE (-2 3775);
FORCEADD OFFPAGE..1
(-2575 4050);
FORCEPROP 2 LAST $XR1 91 
J 0
(-2886 4050);
DISPLAY 0.638298 (-2886 4050);
PAINT MONO (-2886 4050);
FORCEPROP 2 LAST $XR0 24 
J 0
(-2796 4050);
DISPLAY 0.638298 (-2796 4050);
PAINT MONO (-2796 4050);
FORCEPROP 2 LAST CDS_LIB standard
J 0
(-2575 4050);
PAINT MONO (-2575 4050);
DISPLAY INVISIBLE (-2575 4050);
FORCEPROP 1 LAST OFFPAGE TRUE
J 0
(-2250 3925);
DISPLAY 0.872340 (-2250 3925);
DISPLAY INVISIBLE (-2250 3925);
FORCEPROP 1 LAST COMMENT_BODY TRUE
J 0
(-2450 3950);
DISPLAY 0.872340 (-2450 3950);
PAINT GREEN (-2450 3950);
DISPLAY INVISIBLE (-2450 3950);
FORCEPROP 2 LAST PATH I109
J 0
(-2525 4125);
DISPLAY 1.021277 (-2525 4125);
DISPLAY INVISIBLE (-2525 4125);
FORCEADD Q_RES..2
(-1425 -125);
FORCEPROP 1 LAST PART_NUMBER CS31002FB08
J 0
(-1385 -250);
DISPLAY 0.978723 (-1385 -250);
DISPLAY INVISIBLE (-1385 -250);
FORCEPROP 1 LAST TOLERANCE 1%
J 0
(-1380 -100);
DISPLAY 0.978723 (-1380 -100);
FORCEPROP 1 LAST PACK_TYPE 0402LF
J 0
(-1385 -300);
DISPLAY 0.978723 (-1385 -300);
FORCEPROP 1 LAST VALUE 10K
J 0
(-1380 -50);
DISPLAY 0.978723 (-1380 -50);
FORCEPROP 1 LAST MATERIAL CHIP
J 0
(-1385 -200);
DISPLAY 0.978723 (-1385 -200);
FORCEPROP 1 LAST WATTAGE 1/16W
J 0
(-1385 -150);
DISPLAY 0.978723 (-1385 -150);
FORCEPROP 1 LAST $LOCATION R34
J 0
(-1380 0);
DISPLAY 0.978723 (-1380 0);
FORCEPROP 1 LASTPIN (-1425 -25) $PN 1
J 0
(-1420 -63);
DISPLAY 0.787234 (-1420 -63);
FORCEPROP 1 LASTPIN (-1425 -225) $PN 2
J 0
(-1420 -215);
DISPLAY 0.787234 (-1420 -215);
FORCEPROP 2 LAST CDS_LIB pure_quanta
J 0
(-1425 -125);
PAINT MONO (-1425 -125);
DISPLAY INVISIBLE (-1425 -125);
FORCEPROP 2 LAST CDS_LOCATION R34
J 0
(-1375 100);
DISPLAY 1.021277 (-1375 100);
DISPLAY INVISIBLE (-1375 100);
FORCEPROP 2 LAST $SEC 1
J 0
(-1375 100);
DISPLAY 0.680851 (-1375 100);
PAINT MONO (-1375 100);
DISPLAY INVISIBLE (-1375 100);
FORCEPROP 2 LAST CDS_SEC 1
J 0
(-1375 100);
DISPLAY 1.021277 (-1375 100);
DISPLAY INVISIBLE (-1375 100);
FORCEPROP 1 LAST PATH I11
J 0
(-1375 50);
DISPLAY 0.978723 (-1375 50);
PAINT WHITE (-1375 50);
DISPLAY INVISIBLE (-1375 50);
FORCEADD TAP..1
R 2
(-1650 3825);
FORCEPROP 3 LASTPIN (-1600 3825) SIG_NAME M_E_CPU0_SA_CA<2>
J 0
(-1590 3835);
DISPLAY 0.659574 (-1590 3835);
PAINT MONO (-1590 3835);
DISPLAY INVISIBLE (-1590 3835);
FORCEPROP 1 LASTPIN (-1600 3825) BN 2
J 2
(-1588 3833);
DISPLAY 0.680851 (-1588 3833);
PAINT GREEN (-1588 3833);
FORCEPROP 2 LAST CDS_LIB standard
J 0
(-1650 3825);
DISPLAY INVISIBLE (-1650 3825);
FORCEPROP 1 LAST BODY_TYPE PLUMBING
J 2
(-1650 3875);
DISPLAY 0.872340 (-1650 3875);
PAINT GREEN (-1650 3875);
DISPLAY INVISIBLE (-1650 3875);
FORCEPROP 1 LAST HDL_TAP TRUE
J 2
(-1975 3700);
DISPLAY 0.872340 (-1975 3700);
DISPLAY INVISIBLE (-1975 3700);
FORCEPROP 1 LAST PATH I110
J 2
(-1648 3825);
DISPLAY 0.872340 (-1648 3825);
PAINT GREEN (-1648 3825);
DISPLAY INVISIBLE (-1648 3825);
FORCEADD TAP..1
R 2
(-1650 3875);
FORCEPROP 3 LASTPIN (-1600 3875) SIG_NAME M_E_CPU0_SA_CA<3>
J 0
(-1590 3885);
DISPLAY 0.659574 (-1590 3885);
PAINT MONO (-1590 3885);
DISPLAY INVISIBLE (-1590 3885);
FORCEPROP 1 LASTPIN (-1600 3875) BN 3
J 2
(-1588 3883);
DISPLAY 0.680851 (-1588 3883);
PAINT GREEN (-1588 3883);
FORCEPROP 2 LAST CDS_LIB standard
J 0
(-1650 3875);
DISPLAY INVISIBLE (-1650 3875);
FORCEPROP 1 LAST BODY_TYPE PLUMBING
J 2
(-1650 3925);
DISPLAY 0.872340 (-1650 3925);
PAINT GREEN (-1650 3925);
DISPLAY INVISIBLE (-1650 3925);
FORCEPROP 1 LAST HDL_TAP TRUE
J 2
(-1975 3750);
DISPLAY 0.872340 (-1975 3750);
DISPLAY INVISIBLE (-1975 3750);
FORCEPROP 1 LAST PATH I111
J 2
(-1648 3875);
DISPLAY 0.872340 (-1648 3875);
PAINT GREEN (-1648 3875);
DISPLAY INVISIBLE (-1648 3875);
FORCEADD TAP..1
R 2
(-1650 3925);
FORCEPROP 3 LASTPIN (-1600 3925) SIG_NAME M_E_CPU0_SA_CA<4>
J 0
(-1590 3935);
DISPLAY 0.659574 (-1590 3935);
PAINT MONO (-1590 3935);
DISPLAY INVISIBLE (-1590 3935);
FORCEPROP 1 LASTPIN (-1600 3925) BN 4
J 2
(-1588 3933);
DISPLAY 0.680851 (-1588 3933);
PAINT GREEN (-1588 3933);
FORCEPROP 2 LAST CDS_LIB standard
J 0
(-1650 3925);
DISPLAY INVISIBLE (-1650 3925);
FORCEPROP 1 LAST BODY_TYPE PLUMBING
J 2
(-1650 3975);
DISPLAY 0.872340 (-1650 3975);
PAINT GREEN (-1650 3975);
DISPLAY INVISIBLE (-1650 3975);
FORCEPROP 1 LAST HDL_TAP TRUE
J 2
(-1975 3800);
DISPLAY 0.872340 (-1975 3800);
DISPLAY INVISIBLE (-1975 3800);
FORCEPROP 1 LAST PATH I112
J 2
(-1648 3925);
DISPLAY 0.872340 (-1648 3925);
PAINT GREEN (-1648 3925);
DISPLAY INVISIBLE (-1648 3925);
FORCEADD TAP..1
R 2
(-1650 4025);
FORCEPROP 3 LASTPIN (-1600 4025) SIG_NAME M_E_CPU0_SA_CA<6>
J 0
(-1590 4035);
DISPLAY 0.659574 (-1590 4035);
PAINT MONO (-1590 4035);
DISPLAY INVISIBLE (-1590 4035);
FORCEPROP 1 LASTPIN (-1600 4025) BN 6
J 2
(-1588 4033);
DISPLAY 0.680851 (-1588 4033);
PAINT GREEN (-1588 4033);
FORCEPROP 2 LAST CDS_LIB standard
J 0
(-1650 4025);
DISPLAY INVISIBLE (-1650 4025);
FORCEPROP 1 LAST BODY_TYPE PLUMBING
J 2
(-1650 4075);
DISPLAY 0.872340 (-1650 4075);
PAINT GREEN (-1650 4075);
DISPLAY INVISIBLE (-1650 4075);
FORCEPROP 1 LAST HDL_TAP TRUE
J 2
(-1975 3900);
DISPLAY 0.872340 (-1975 3900);
DISPLAY INVISIBLE (-1975 3900);
FORCEPROP 1 LAST PATH I113
J 2
(-1648 4025);
DISPLAY 0.872340 (-1648 4025);
PAINT GREEN (-1648 4025);
DISPLAY INVISIBLE (-1648 4025);
FORCEADD TAP..1
R 2
(-1650 3975);
FORCEPROP 3 LASTPIN (-1600 3975) SIG_NAME M_E_CPU0_SA_CA<5>
J 0
(-1590 3985);
DISPLAY 0.659574 (-1590 3985);
PAINT MONO (-1590 3985);
DISPLAY INVISIBLE (-1590 3985);
FORCEPROP 1 LASTPIN (-1600 3975) BN 5
J 2
(-1588 3983);
DISPLAY 0.680851 (-1588 3983);
PAINT GREEN (-1588 3983);
FORCEPROP 2 LAST CDS_LIB standard
J 0
(-1650 3975);
DISPLAY INVISIBLE (-1650 3975);
FORCEPROP 1 LAST BODY_TYPE PLUMBING
J 2
(-1650 4025);
DISPLAY 0.872340 (-1650 4025);
PAINT GREEN (-1650 4025);
DISPLAY INVISIBLE (-1650 4025);
FORCEPROP 1 LAST HDL_TAP TRUE
J 2
(-1975 3850);
DISPLAY 0.872340 (-1975 3850);
DISPLAY INVISIBLE (-1975 3850);
FORCEPROP 1 LAST PATH I114
J 2
(-1648 3975);
DISPLAY 0.872340 (-1648 3975);
PAINT GREEN (-1648 3975);
DISPLAY INVISIBLE (-1648 3975);
FORCEADD TAP..1
(0 3925);
FORCEPROP 3 LASTPIN (-50 3925) SIG_NAME M_E_CPU0_SA_DQ<29>
J 0
(-40 3935);
DISPLAY 0.659574 (-40 3935);
PAINT MONO (-40 3935);
DISPLAY INVISIBLE (-40 3935);
FORCEPROP 1 LASTPIN (-50 3925) BN 29
J 0
(-62 3933);
DISPLAY 0.680851 (-62 3933);
PAINT GREEN (-62 3933);
FORCEPROP 2 LAST CDS_LIB standard
J 0
(0 3925);
DISPLAY INVISIBLE (0 3925);
FORCEPROP 1 LAST BODY_TYPE PLUMBING
J 0
(0 3975);
DISPLAY 0.872340 (0 3975);
PAINT GREEN (0 3975);
DISPLAY INVISIBLE (0 3975);
FORCEPROP 1 LAST HDL_TAP TRUE
J 0
(325 3800);
DISPLAY 0.872340 (325 3800);
DISPLAY INVISIBLE (325 3800);
FORCEPROP 1 LAST PATH I115
J 0
(-2 3925);
DISPLAY 0.872340 (-2 3925);
PAINT GREEN (-2 3925);
DISPLAY INVISIBLE (-2 3925);
FORCEADD TAP..1
(0 3825);
FORCEPROP 3 LASTPIN (-50 3825) SIG_NAME M_E_CPU0_SA_DQ<27>
J 0
(-40 3835);
DISPLAY 0.659574 (-40 3835);
PAINT MONO (-40 3835);
DISPLAY INVISIBLE (-40 3835);
FORCEPROP 1 LASTPIN (-50 3825) BN 27
J 0
(-62 3833);
DISPLAY 0.680851 (-62 3833);
PAINT GREEN (-62 3833);
FORCEPROP 2 LAST CDS_LIB standard
J 0
(0 3825);
DISPLAY INVISIBLE (0 3825);
FORCEPROP 1 LAST BODY_TYPE PLUMBING
J 0
(0 3875);
DISPLAY 0.872340 (0 3875);
PAINT GREEN (0 3875);
DISPLAY INVISIBLE (0 3875);
FORCEPROP 1 LAST HDL_TAP TRUE
J 0
(325 3700);
DISPLAY 0.872340 (325 3700);
DISPLAY INVISIBLE (325 3700);
FORCEPROP 1 LAST PATH I116
J 0
(-2 3825);
DISPLAY 0.872340 (-2 3825);
PAINT GREEN (-2 3825);
DISPLAY INVISIBLE (-2 3825);
FORCEADD TAP..1
(0 3875);
FORCEPROP 3 LASTPIN (-50 3875) SIG_NAME M_E_CPU0_SA_DQ<28>
J 0
(-40 3885);
DISPLAY 0.659574 (-40 3885);
PAINT MONO (-40 3885);
DISPLAY INVISIBLE (-40 3885);
FORCEPROP 1 LASTPIN (-50 3875) BN 28
J 0
(-62 3883);
DISPLAY 0.680851 (-62 3883);
PAINT GREEN (-62 3883);
FORCEPROP 2 LAST CDS_LIB standard
J 0
(0 3875);
DISPLAY INVISIBLE (0 3875);
FORCEPROP 1 LAST BODY_TYPE PLUMBING
J 0
(0 3925);
DISPLAY 0.872340 (0 3925);
PAINT GREEN (0 3925);
DISPLAY INVISIBLE (0 3925);
FORCEPROP 1 LAST HDL_TAP TRUE
J 0
(325 3750);
DISPLAY 0.872340 (325 3750);
DISPLAY INVISIBLE (325 3750);
FORCEPROP 1 LAST PATH I117
J 0
(-2 3875);
DISPLAY 0.872340 (-2 3875);
PAINT GREEN (-2 3875);
DISPLAY INVISIBLE (-2 3875);
FORCEADD TAP..1
(0 3975);
FORCEPROP 3 LASTPIN (-50 3975) SIG_NAME M_E_CPU0_SA_DQ<30>
J 0
(-40 3985);
DISPLAY 0.659574 (-40 3985);
PAINT MONO (-40 3985);
DISPLAY INVISIBLE (-40 3985);
FORCEPROP 1 LASTPIN (-50 3975) BN 30
J 0
(-62 3983);
DISPLAY 0.680851 (-62 3983);
PAINT GREEN (-62 3983);
FORCEPROP 2 LAST CDS_LIB standard
J 0
(0 3975);
DISPLAY INVISIBLE (0 3975);
FORCEPROP 1 LAST BODY_TYPE PLUMBING
J 0
(0 4025);
DISPLAY 0.872340 (0 4025);
PAINT GREEN (0 4025);
DISPLAY INVISIBLE (0 4025);
FORCEPROP 1 LAST HDL_TAP TRUE
J 0
(325 3850);
DISPLAY 0.872340 (325 3850);
DISPLAY INVISIBLE (325 3850);
FORCEPROP 1 LAST PATH I118
J 0
(-2 3975);
DISPLAY 0.872340 (-2 3975);
PAINT GREEN (-2 3975);
DISPLAY INVISIBLE (-2 3975);
FORCEADD TAP..1
(0 4025);
FORCEPROP 3 LASTPIN (-50 4025) SIG_NAME M_E_CPU0_SA_DQ<31>
J 0
(-40 4035);
DISPLAY 0.659574 (-40 4035);
PAINT MONO (-40 4035);
DISPLAY INVISIBLE (-40 4035);
FORCEPROP 1 LASTPIN (-50 4025) BN 31
J 0
(-62 4033);
DISPLAY 0.680851 (-62 4033);
PAINT GREEN (-62 4033);
FORCEPROP 2 LAST CDS_LIB standard
J 0
(0 4025);
DISPLAY INVISIBLE (0 4025);
FORCEPROP 1 LAST BODY_TYPE PLUMBING
J 0
(0 4075);
DISPLAY 0.872340 (0 4075);
PAINT GREEN (0 4075);
DISPLAY INVISIBLE (0 4075);
FORCEPROP 1 LAST HDL_TAP TRUE
J 0
(325 3900);
DISPLAY 0.872340 (325 3900);
DISPLAY INVISIBLE (325 3900);
FORCEPROP 1 LAST PATH I119
J 0
(-2 4025);
DISPLAY 0.872340 (-2 4025);
PAINT GREEN (-2 4025);
DISPLAY INVISIBLE (-2 4025);
FORCEADD SCONN288_ADR50017P130CC..1
(-825 2300);
FORCEPROP 1 LAST PART_NUMBER DFHST8FS461
J 0
(-1270 4322);
DISPLAY 0.723404 (-1270 4322);
PAINT GREEN (-1270 4322);
DISPLAY INVISIBLE (-1270 4322);
FORCEPROP 1 LAST MATERIAL IO
J 0
(-1270 4195);
DISPLAY 0.723404 (-1270 4195);
PAINT GREEN (-1270 4195);
FORCEPROP 2 LAST VALUE SCONN288_ADR50017-P130CC
J 0
(-1275 4425);
DISPLAY 1.021277 (-1275 4425);
FORCEPROP 2 LAST PART_TYPE SMLF
J 0
(-1275 4475);
DISPLAY 1.021277 (-1275 4475);
FORCEPROP 1 LAST $LOCATION J9
J 0
(-1275 4375);
DISPLAY 0.723404 (-1275 4375);
PAINT GREEN (-1275 4375);
FORCEPROP 0 LASTPIN (-1425 1675) $PN 62
J 2
(-1435 1685);
DISPLAY 0.680851 (-1435 1685);
PAINT MONO (-1435 1685);
FORCEPROP 0 LASTPIN (-1425 3725) $PN 66
J 2
(-1435 3735);
DISPLAY 0.680851 (-1435 3735);
PAINT MONO (-1435 3735);
FORCEPROP 0 LASTPIN (-1425 3325) $PN 76
J 2
(-1435 3335);
DISPLAY 0.680851 (-1435 3335);
PAINT MONO (-1435 3335);
FORCEPROP 0 LASTPIN (-1425 3775) $PN 211
J 2
(-1435 3785);
DISPLAY 0.680851 (-1435 3785);
PAINT MONO (-1435 3785);
FORCEPROP 0 LASTPIN (-1425 3375) $PN 221
J 2
(-1435 3385);
DISPLAY 0.680851 (-1435 3385);
PAINT MONO (-1435 3385);
FORCEPROP 0 LASTPIN (-1425 3825) $PN 68
J 2
(-1435 3835);
DISPLAY 0.680851 (-1435 3835);
PAINT MONO (-1435 3835);
FORCEPROP 0 LASTPIN (-1425 3425) $PN 78
J 2
(-1435 3435);
DISPLAY 0.680851 (-1435 3435);
PAINT MONO (-1435 3435);
FORCEPROP 0 LASTPIN (-1425 3875) $PN 213
J 2
(-1435 3885);
DISPLAY 0.680851 (-1435 3885);
PAINT MONO (-1435 3885);
FORCEPROP 0 LASTPIN (-1425 3475) $PN 223
J 2
(-1435 3485);
DISPLAY 0.680851 (-1435 3485);
PAINT MONO (-1435 3485);
FORCEPROP 0 LASTPIN (-1425 3925) $PN 70
J 2
(-1435 3935);
DISPLAY 0.680851 (-1435 3935);
PAINT MONO (-1435 3935);
FORCEPROP 0 LASTPIN (-1425 3525) $PN 80
J 2
(-1435 3535);
DISPLAY 0.680851 (-1435 3535);
PAINT MONO (-1435 3535);
FORCEPROP 0 LASTPIN (-1425 3975) $PN 215
J 2
(-1435 3985);
DISPLAY 0.680851 (-1435 3985);
PAINT MONO (-1435 3985);
FORCEPROP 0 LASTPIN (-1425 3575) $PN 225
J 2
(-1435 3585);
DISPLAY 0.680851 (-1435 3585);
PAINT MONO (-1435 3585);
FORCEPROP 0 LASTPIN (-1425 4025) $PN 72
J 2
(-1435 4035);
DISPLAY 0.680851 (-1435 4035);
PAINT MONO (-1435 4035);
FORCEPROP 0 LASTPIN (-1425 3625) $PN 82
J 2
(-1435 3635);
DISPLAY 0.680851 (-1435 3635);
PAINT MONO (-1435 3635);
FORCEPROP 0 LASTPIN (-1425 2275) $PN 51
J 2
(-1435 2285);
DISPLAY 0.680851 (-1435 2285);
PAINT MONO (-1435 2285);
FORCEPROP 0 LASTPIN (-1425 1825) $PN 96
J 2
(-1435 1835);
DISPLAY 0.680851 (-1435 1835);
PAINT MONO (-1435 1835);
FORCEPROP 0 LASTPIN (-1425 2325) $PN 53
J 2
(-1435 2335);
DISPLAY 0.680851 (-1435 2335);
PAINT MONO (-1435 2335);
FORCEPROP 0 LASTPIN (-1425 1875) $PN 98
J 2
(-1435 1885);
DISPLAY 0.680851 (-1435 1885);
PAINT MONO (-1435 1885);
FORCEPROP 0 LASTPIN (-1425 2375) $PN 196
J 2
(-1435 2385);
DISPLAY 0.680851 (-1435 2385);
PAINT MONO (-1435 2385);
FORCEPROP 0 LASTPIN (-1425 1925) $PN 241
J 2
(-1435 1935);
DISPLAY 0.680851 (-1435 1935);
PAINT MONO (-1435 1935);
FORCEPROP 0 LASTPIN (-1425 2425) $PN 198
J 2
(-1435 2435);
DISPLAY 0.680851 (-1435 2435);
PAINT MONO (-1435 2435);
FORCEPROP 0 LASTPIN (-1425 1975) $PN 243
J 2
(-1435 1985);
DISPLAY 0.680851 (-1435 1985);
PAINT MONO (-1435 1985);
FORCEPROP 0 LASTPIN (-1425 2475) $PN 58
J 2
(-1435 2485);
DISPLAY 0.680851 (-1435 2485);
PAINT MONO (-1435 2485);
FORCEPROP 0 LASTPIN (-1425 2025) $PN 89
J 2
(-1435 2035);
DISPLAY 0.680851 (-1435 2035);
PAINT MONO (-1435 2035);
FORCEPROP 0 LASTPIN (-1425 2525) $PN 60
J 2
(-1435 2535);
DISPLAY 0.680851 (-1435 2535);
PAINT MONO (-1435 2535);
FORCEPROP 0 LASTPIN (-1425 2075) $PN 91
J 2
(-1435 2085);
DISPLAY 0.680851 (-1435 2085);
PAINT MONO (-1435 2085);
FORCEPROP 0 LASTPIN (-1425 2575) $PN 203
J 2
(-1435 2585);
DISPLAY 0.680851 (-1435 2585);
PAINT MONO (-1435 2585);
FORCEPROP 0 LASTPIN (-1425 2125) $PN 234
J 2
(-1435 2135);
DISPLAY 0.680851 (-1435 2135);
PAINT MONO (-1435 2135);
FORCEPROP 0 LASTPIN (-1425 2625) $PN 205
J 2
(-1435 2635);
DISPLAY 0.680851 (-1435 2635);
PAINT MONO (-1435 2635);
FORCEPROP 0 LASTPIN (-1425 2175) $PN 236
J 2
(-1435 2185);
DISPLAY 0.680851 (-1435 2185);
PAINT MONO (-1435 2185);
FORCEPROP 0 LASTPIN (-1425 2725) $PN 218
J 2
(-1435 2735);
DISPLAY 0.680851 (-1435 2735);
PAINT MONO (-1435 2735);
FORCEPROP 0 LASTPIN (-1425 2775) $PN 217
J 2
(-1435 2785);
DISPLAY 0.680851 (-1435 2785);
PAINT MONO (-1435 2785);
FORCEPROP 0 LASTPIN (-1425 3025) $PN 64
J 2
(-1435 3035);
DISPLAY 0.680851 (-1435 3035);
PAINT MONO (-1435 3035);
FORCEPROP 0 LASTPIN (-1425 2875) $PN 84
J 2
(-1435 2885);
DISPLAY 0.680851 (-1435 2885);
PAINT MONO (-1435 2885);
FORCEPROP 0 LASTPIN (-1425 3075) $PN 209
J 2
(-1435 3085);
DISPLAY 0.680851 (-1435 3085);
PAINT MONO (-1435 3085);
FORCEPROP 0 LASTPIN (-1425 2925) $PN 229
J 2
(-1435 2935);
DISPLAY 0.680851 (-1435 2935);
PAINT MONO (-1435 2935);
FORCEPROP 0 LASTPIN (-225 2475) $PN 7
J 0
(-215 2485);
DISPLAY 0.680851 (-215 2485);
PAINT MONO (-215 2485);
FORCEPROP 0 LASTPIN (-225 825) $PN 100
J 0
(-215 835);
DISPLAY 0.680851 (-215 835);
PAINT MONO (-215 835);
FORCEPROP 0 LASTPIN (-225 2525) $PN 9
J 0
(-215 2535);
DISPLAY 0.680851 (-215 2535);
PAINT MONO (-215 2535);
FORCEPROP 0 LASTPIN (-225 875) $PN 102
J 0
(-215 885);
DISPLAY 0.680851 (-215 885);
PAINT MONO (-215 885);
FORCEPROP 0 LASTPIN (-225 2575) $PN 152
J 0
(-215 2585);
DISPLAY 0.680851 (-215 2585);
PAINT MONO (-215 2585);
FORCEPROP 0 LASTPIN (-225 925) $PN 245
J 0
(-215 935);
DISPLAY 0.680851 (-215 935);
PAINT MONO (-215 935);
FORCEPROP 0 LASTPIN (-225 2625) $PN 154
J 0
(-215 2635);
DISPLAY 0.680851 (-215 2635);
PAINT MONO (-215 2635);
FORCEPROP 0 LASTPIN (-225 975) $PN 247
J 0
(-215 985);
DISPLAY 0.680851 (-215 985);
PAINT MONO (-215 985);
FORCEPROP 0 LASTPIN (-225 2675) $PN 14
J 0
(-215 2685);
DISPLAY 0.680851 (-215 2685);
PAINT MONO (-215 2685);
FORCEPROP 0 LASTPIN (-225 1025) $PN 107
J 0
(-215 1035);
DISPLAY 0.680851 (-215 1035);
PAINT MONO (-215 1035);
FORCEPROP 0 LASTPIN (-225 2725) $PN 16
J 0
(-215 2735);
DISPLAY 0.680851 (-215 2735);
PAINT MONO (-215 2735);
FORCEPROP 0 LASTPIN (-225 1075) $PN 109
J 0
(-215 1085);
DISPLAY 0.680851 (-215 1085);
PAINT MONO (-215 1085);
FORCEPROP 0 LASTPIN (-225 2775) $PN 159
J 0
(-215 2785);
DISPLAY 0.680851 (-215 2785);
PAINT MONO (-215 2785);
FORCEPROP 0 LASTPIN (-225 1125) $PN 252
J 0
(-215 1135);
DISPLAY 0.680851 (-215 1135);
PAINT MONO (-215 1135);
FORCEPROP 0 LASTPIN (-225 2825) $PN 161
J 0
(-215 2835);
DISPLAY 0.680851 (-215 2835);
PAINT MONO (-215 2835);
FORCEPROP 0 LASTPIN (-225 1175) $PN 254
J 0
(-215 1185);
DISPLAY 0.680851 (-215 1185);
PAINT MONO (-215 1185);
FORCEPROP 0 LASTPIN (-225 2875) $PN 18
J 0
(-215 2885);
DISPLAY 0.680851 (-215 2885);
PAINT MONO (-215 2885);
FORCEPROP 0 LASTPIN (-225 1225) $PN 111
J 0
(-215 1235);
DISPLAY 0.680851 (-215 1235);
PAINT MONO (-215 1235);
FORCEPROP 0 LASTPIN (-225 2925) $PN 20
J 0
(-215 2935);
DISPLAY 0.680851 (-215 2935);
PAINT MONO (-215 2935);
FORCEPROP 0 LASTPIN (-225 1275) $PN 113
J 0
(-215 1285);
DISPLAY 0.680851 (-215 1285);
PAINT MONO (-215 1285);
FORCEPROP 0 LASTPIN (-225 2975) $PN 163
J 0
(-215 2985);
DISPLAY 0.680851 (-215 2985);
PAINT MONO (-215 2985);
FORCEPROP 0 LASTPIN (-225 1325) $PN 256
J 0
(-215 1335);
DISPLAY 0.680851 (-215 1335);
PAINT MONO (-215 1335);
FORCEPROP 0 LASTPIN (-225 3025) $PN 165
J 0
(-215 3035);
DISPLAY 0.680851 (-215 3035);
PAINT MONO (-215 3035);
FORCEPROP 0 LASTPIN (-225 1375) $PN 258
J 0
(-215 1385);
DISPLAY 0.680851 (-215 1385);
PAINT MONO (-215 1385);
FORCEPROP 0 LASTPIN (-225 3075) $PN 25
J 0
(-215 3085);
DISPLAY 0.680851 (-215 3085);
PAINT MONO (-215 3085);
FORCEPROP 0 LASTPIN (-225 1425) $PN 118
J 0
(-215 1435);
DISPLAY 0.680851 (-215 1435);
PAINT MONO (-215 1435);
FORCEPROP 0 LASTPIN (-225 3125) $PN 27
J 0
(-215 3135);
DISPLAY 0.680851 (-215 3135);
PAINT MONO (-215 3135);
FORCEPROP 0 LASTPIN (-225 1475) $PN 120
J 0
(-215 1485);
DISPLAY 0.680851 (-215 1485);
PAINT MONO (-215 1485);
FORCEPROP 0 LASTPIN (-225 3175) $PN 170
J 0
(-215 3185);
DISPLAY 0.680851 (-215 3185);
PAINT MONO (-215 3185);
FORCEPROP 0 LASTPIN (-225 1525) $PN 263
J 0
(-215 1535);
DISPLAY 0.680851 (-215 1535);
PAINT MONO (-215 1535);
FORCEPROP 0 LASTPIN (-225 3225) $PN 172
J 0
(-215 3235);
DISPLAY 0.680851 (-215 3235);
PAINT MONO (-215 3235);
FORCEPROP 0 LASTPIN (-225 1575) $PN 265
J 0
(-215 1585);
DISPLAY 0.680851 (-215 1585);
PAINT MONO (-215 1585);
FORCEPROP 0 LASTPIN (-225 3275) $PN 29
J 0
(-215 3285);
DISPLAY 0.680851 (-215 3285);
PAINT MONO (-215 3285);
FORCEPROP 0 LASTPIN (-225 1625) $PN 122
J 0
(-215 1635);
DISPLAY 0.680851 (-215 1635);
PAINT MONO (-215 1635);
FORCEPROP 0 LASTPIN (-225 3325) $PN 31
J 0
(-215 3335);
DISPLAY 0.680851 (-215 3335);
PAINT MONO (-215 3335);
FORCEPROP 0 LASTPIN (-225 1675) $PN 124
J 0
(-215 1685);
DISPLAY 0.680851 (-215 1685);
PAINT MONO (-215 1685);
FORCEPROP 0 LASTPIN (-225 3375) $PN 174
J 0
(-215 3385);
DISPLAY 0.680851 (-215 3385);
PAINT MONO (-215 3385);
FORCEPROP 0 LASTPIN (-225 1725) $PN 267
J 0
(-215 1735);
DISPLAY 0.680851 (-215 1735);
PAINT MONO (-215 1735);
FORCEPROP 0 LASTPIN (-225 3425) $PN 176
J 0
(-215 3435);
DISPLAY 0.680851 (-215 3435);
PAINT MONO (-215 3435);
FORCEPROP 0 LASTPIN (-225 1775) $PN 269
J 0
(-215 1785);
DISPLAY 0.680851 (-215 1785);
PAINT MONO (-215 1785);
FORCEPROP 0 LASTPIN (-225 3475) $PN 36
J 0
(-215 3485);
DISPLAY 0.680851 (-215 3485);
PAINT MONO (-215 3485);
FORCEPROP 0 LASTPIN (-225 1825) $PN 129
J 0
(-215 1835);
DISPLAY 0.680851 (-215 1835);
PAINT MONO (-215 1835);
FORCEPROP 0 LASTPIN (-225 3525) $PN 38
J 0
(-215 3535);
DISPLAY 0.680851 (-215 3535);
PAINT MONO (-215 3535);
FORCEPROP 0 LASTPIN (-225 1875) $PN 131
J 0
(-215 1885);
DISPLAY 0.680851 (-215 1885);
PAINT MONO (-215 1885);
FORCEPROP 0 LASTPIN (-225 3575) $PN 181
J 0
(-215 3585);
DISPLAY 0.680851 (-215 3585);
PAINT MONO (-215 3585);
FORCEPROP 0 LASTPIN (-225 1925) $PN 274
J 0
(-215 1935);
DISPLAY 0.680851 (-215 1935);
PAINT MONO (-215 1935);
FORCEPROP 0 LASTPIN (-225 3625) $PN 183
J 0
(-215 3635);
DISPLAY 0.680851 (-215 3635);
PAINT MONO (-215 3635);
FORCEPROP 0 LASTPIN (-225 1975) $PN 276
J 0
(-215 1985);
DISPLAY 0.680851 (-215 1985);
PAINT MONO (-215 1985);
FORCEPROP 0 LASTPIN (-225 3675) $PN 40
J 0
(-215 3685);
DISPLAY 0.680851 (-215 3685);
PAINT MONO (-215 3685);
FORCEPROP 0 LASTPIN (-225 2025) $PN 133
J 0
(-215 2035);
DISPLAY 0.680851 (-215 2035);
PAINT MONO (-215 2035);
FORCEPROP 0 LASTPIN (-225 3725) $PN 42
J 0
(-215 3735);
DISPLAY 0.680851 (-215 3735);
PAINT MONO (-215 3735);
FORCEPROP 0 LASTPIN (-225 2075) $PN 135
J 0
(-215 2085);
DISPLAY 0.680851 (-215 2085);
PAINT MONO (-215 2085);
FORCEPROP 0 LASTPIN (-225 3775) $PN 185
J 0
(-215 3785);
DISPLAY 0.680851 (-215 3785);
PAINT MONO (-215 3785);
FORCEPROP 0 LASTPIN (-225 2125) $PN 278
J 0
(-215 2135);
DISPLAY 0.680851 (-215 2135);
PAINT MONO (-215 2135);
FORCEPROP 0 LASTPIN (-225 3825) $PN 187
J 0
(-215 3835);
DISPLAY 0.680851 (-215 3835);
PAINT MONO (-215 3835);
FORCEPROP 0 LASTPIN (-225 2175) $PN 280
J 0
(-215 2185);
DISPLAY 0.680851 (-215 2185);
PAINT MONO (-215 2185);
FORCEPROP 0 LASTPIN (-225 3875) $PN 47
J 0
(-215 3885);
DISPLAY 0.680851 (-215 3885);
PAINT MONO (-215 3885);
FORCEPROP 0 LASTPIN (-225 2225) $PN 140
J 0
(-215 2235);
DISPLAY 0.680851 (-215 2235);
PAINT MONO (-215 2235);
FORCEPROP 0 LASTPIN (-225 3925) $PN 49
J 0
(-215 3935);
DISPLAY 0.680851 (-215 3935);
PAINT MONO (-215 3935);
FORCEPROP 0 LASTPIN (-225 2275) $PN 142
J 0
(-215 2285);
DISPLAY 0.680851 (-215 2285);
PAINT MONO (-215 2285);
FORCEPROP 0 LASTPIN (-225 3975) $PN 192
J 0
(-215 3985);
DISPLAY 0.680851 (-215 3985);
PAINT MONO (-215 3985);
FORCEPROP 0 LASTPIN (-225 2325) $PN 285
J 0
(-215 2335);
DISPLAY 0.680851 (-215 2335);
PAINT MONO (-215 2335);
FORCEPROP 0 LASTPIN (-225 4025) $PN 194
J 0
(-215 4035);
DISPLAY 0.680851 (-215 4035);
PAINT MONO (-215 4035);
FORCEPROP 0 LASTPIN (-225 2375) $PN 287
J 0
(-215 2385);
DISPLAY 0.680851 (-215 2385);
PAINT MONO (-215 2385);
FORCEPROP 0 LASTPIN (-1425 1525) $PN 148
J 2
(-1435 1535);
DISPLAY 0.680851 (-1435 1535);
PAINT MONO (-1435 1535);
FORCEPROP 0 LASTPIN (-1425 1425) $PN 4
J 2
(-1435 1435);
DISPLAY 0.680851 (-1435 1435);
PAINT MONO (-1435 1435);
FORCEPROP 0 LASTPIN (-1425 1475) $PN 5
J 2
(-1435 1485);
DISPLAY 0.680851 (-1435 1485);
PAINT MONO (-1435 1485);
FORCEPROP 0 LASTPIN (-1425 625) $PN 86
J 2
(-1435 635);
DISPLAY 0.680851 (-1435 635);
PAINT MONO (-1435 635);
FORCEPROP 0 LASTPIN (-1425 575) $PN 87
J 2
(-1435 585);
DISPLAY 0.680851 (-1435 585);
PAINT MONO (-1435 585);
FORCEPROP 0 LASTPIN (-1425 3225) $PN 74
J 2
(-1435 3235);
DISPLAY 0.680851 (-1435 3235);
PAINT MONO (-1435 3235);
FORCEPROP 0 LASTPIN (-1425 3175) $PN 227
J 2
(-1435 3185);
DISPLAY 0.680851 (-1435 3185);
PAINT MONO (-1435 3185);
FORCEPROP 0 LASTPIN (-1425 1175) $PN 147
J 2
(-1435 1185);
DISPLAY 0.680851 (-1435 1185);
PAINT MONO (-1435 1185);
FORCEPROP 0 LASTPIN (-1425 1725) $PN 207
J 2
(-1435 1735);
DISPLAY 0.680851 (-1435 1735);
PAINT MONO (-1435 1735);
FORCEPROP 0 LASTPIN (-1425 775) $PN 2
J 2
(-1435 785);
DISPLAY 0.680851 (-1435 785);
PAINT MONO (-1435 785);
FORCEPROP 0 LASTPIN (-1425 825) $PN 144
J 2
(-1435 835);
DISPLAY 0.680851 (-1435 835);
PAINT MONO (-1435 835);
FORCEPROP 0 LASTPIN (-1425 875) $PN 149
J 2
(-1435 885);
DISPLAY 0.680851 (-1435 885);
PAINT MONO (-1435 885);
FORCEPROP 0 LASTPIN (-1425 925) $PN 150
J 2
(-1435 935);
DISPLAY 0.680851 (-1435 935);
PAINT MONO (-1435 935);
FORCEPROP 0 LASTPIN (-1425 975) $PN 220
J 2
(-1435 985);
DISPLAY 0.680851 (-1435 985);
PAINT MONO (-1435 985);
FORCEPROP 0 LASTPIN (-1425 1025) $PN 231
J 2
(-1435 1035);
DISPLAY 0.680851 (-1435 1035);
PAINT MONO (-1435 1035);
FORCEPROP 0 LASTPIN (-1425 1075) $PN 232
J 2
(-1435 1085);
DISPLAY 0.680851 (-1435 1085);
PAINT MONO (-1435 1085);
FORCEPROP 0 LASTPIN (-1425 1575) $PN 3
J 2
(-1435 1585);
DISPLAY 0.680851 (-1435 1585);
PAINT MONO (-1435 1585);
FORCEPROP 1 LAST NEEDS_NO_SIZE TRUE
J 0
(-825 2300);
DISPLAY 0.723404 (-825 2300);
PAINT GREEN (-825 2300);
DISPLAY INVISIBLE (-825 2300);
FORCEPROP 1 LAST CDS_LMAN_SYM_OUTLINE -450,1875,450,-1875
J 0
(-825 2300);
DISPLAY 0.468085 (-825 2300);
PAINT GREEN (-825 2300);
DISPLAY INVISIBLE (-825 2300);
FORCEPROP 2 LAST CDS_LIB pure_quanta
J 0
(-825 2300);
DISPLAY INVISIBLE (-825 2300);
FORCEPROP 2 LAST CDS_LOCATION J9
J 0
(-1275 4525);
DISPLAY 1.021277 (-1275 4525);
DISPLAY INVISIBLE (-1275 4525);
FORCEPROP 0 LAST $SEC 1
J 0
(-1250 4525);
DISPLAY 0.680851 (-1250 4525);
PAINT MONO (-1250 4525);
DISPLAY INVISIBLE (-1250 4525);
FORCEPROP 2 LAST CDS_SEC 1
J 0
(-1275 4525);
DISPLAY 1.021277 (-1275 4525);
DISPLAY INVISIBLE (-1275 4525);
FORCEPROP 1 LAST PATH I12
J 0
(-825 2300);
DISPLAY 0.723404 (-825 2300);
PAINT GREEN (-825 2300);
DISPLAY INVISIBLE (-825 2300);
FORCEADD VCC_CORE..1
(1725 475);
FORCEPROP 3 LASTPIN (1725 425) SIG_NAME P3V3_AUX\g
J 0
(1735 435);
DISPLAY 0.659574 (1735 435);
PAINT MONO (1735 435);
DISPLAY INVISIBLE (1735 435);
FORCEPROP 1 LAST HDL_POWER P3V3_AUX
J 1
(1725 525);
DISPLAY 1.148936 (1725 525);
PAINT GREEN (1725 525);
FORCEPROP 2 LAST CDS_LIB logical_power
J 0
(1725 475);
PAINT MONO (1725 475);
DISPLAY INVISIBLE (1725 475);
FORCEPROP 1 LAST PATH I120
J 0
(1775 500);
DISPLAY 0.872340 (1775 500);
PAINT AQUA (1775 500);
DISPLAY INVISIBLE (1775 500);
FORCEADD UNIVERSAL_GND..1
(1725 -225);
FORCEPROP 3 LASTPIN (1725 -175) SIG_NAME GND\g
J 0
(1735 -165);
DISPLAY 0.659574 (1735 -165);
PAINT MONO (1735 -165);
DISPLAY INVISIBLE (1735 -165);
FORCEPROP 2 LAST CDS_LIB logical_power
J 0
(1725 -225);
PAINT MONO (1725 -225);
DISPLAY INVISIBLE (1725 -225);
FORCEPROP 1 LAST HDL_POWER GND
J 1
(1750 -300);
DISPLAY 0.872340 (1750 -300);
PAINT GREEN (1750 -300);
DISPLAY INVISIBLE (1750 -300);
FORCEPROP 1 LAST PATH I121
J 0
(1800 -225);
DISPLAY 0.872340 (1800 -225);
PAINT AQUA (1800 -225);
DISPLAY INVISIBLE (1800 -225);
FORCEADD Q_CAP..1
(1725 150);
FORCEPROP 1 LAST PART_NUMBER CH5221MEB00
J 0
(1775 0);
DISPLAY 0.978723 (1775 0);
DISPLAY INVISIBLE (1775 0);
FORCEPROP 1 LAST PACK_TYPE C0402
J 0
(1775 -50);
DISPLAY 0.978723 (1775 -50);
FORCEPROP 1 LAST TOLERANCE 20%
J 0
(1775 100);
DISPLAY 0.978723 (1775 100);
FORCEPROP 1 LAST VALUE 2.2UF
J 0
(1775 200);
DISPLAY 0.978723 (1775 200);
FORCEPROP 1 LAST MATERIAL X6S
J 0
(1775 50);
DISPLAY 0.978723 (1775 50);
FORCEPROP 1 LAST VOLTAGE 6.3V
J 0
(1775 150);
DISPLAY 0.978723 (1775 150);
FORCEPROP 1 LAST $LOCATION C26
J 0
(1775 250);
DISPLAY 0.978723 (1775 250);
FORCEPROP 1 LASTPIN (1725 250) $PN 1
J 0
(1735 230);
DISPLAY 0.787234 (1735 230);
FORCEPROP 1 LASTPIN (1725 50) $PN 2
J 0
(1735 30);
DISPLAY 0.787234 (1735 30);
FORCEPROP 2 LAST CDS_LIB pure_quanta
J 0
(1725 150);
PAINT MONO (1725 150);
DISPLAY INVISIBLE (1725 150);
FORCEPROP 2 LAST CDS_LOCATION C26
J 0
(1775 350);
DISPLAY 1.021277 (1775 350);
DISPLAY INVISIBLE (1775 350);
FORCEPROP 2 LAST $SEC 1
J 0
(1775 350);
DISPLAY 0.680851 (1775 350);
PAINT MONO (1775 350);
DISPLAY INVISIBLE (1775 350);
FORCEPROP 2 LAST CDS_SEC 1
J 0
(1775 350);
DISPLAY 1.021277 (1775 350);
DISPLAY INVISIBLE (1775 350);
FORCEPROP 1 LAST PATH I122
J 0
(1775 300);
DISPLAY 0.978723 (1775 300);
PAINT WHITE (1775 300);
DISPLAY INVISIBLE (1775 300);
FORCEADD Q_CAP..1
(2725 150);
FORCEPROP 1 LAST PART_NUMBER CH6103KEA00
J 0
(2775 0);
DISPLAY 0.978723 (2775 0);
DISPLAY INVISIBLE (2775 0);
FORCEPROP 1 LAST PACK_TYPE C0805
J 0
(2775 -50);
DISPLAY 0.978723 (2775 -50);
FORCEPROP 1 LAST VOLTAGE 16V
J 0
(2775 150);
DISPLAY 0.978723 (2775 150);
FORCEPROP 1 LAST VALUE 10UF
J 0
(2775 200);
DISPLAY 0.978723 (2775 200);
FORCEPROP 1 LAST TOLERANCE 10%
J 0
(2775 100);
DISPLAY 0.978723 (2775 100);
FORCEPROP 1 LAST MATERIAL X6S
J 0
(2775 50);
DISPLAY 0.978723 (2775 50);
FORCEPROP 1 LAST $LOCATION C27
J 0
(2775 250);
DISPLAY 0.978723 (2775 250);
FORCEPROP 1 LASTPIN (2725 250) $PN 1
J 0
(2735 230);
DISPLAY 0.787234 (2735 230);
FORCEPROP 1 LASTPIN (2725 50) $PN 2
J 0
(2735 30);
DISPLAY 0.787234 (2735 30);
FORCEPROP 2 LAST CDS_LIB pure_quanta
J 0
(2725 150);
PAINT MONO (2725 150);
DISPLAY INVISIBLE (2725 150);
FORCEPROP 2 LAST CDS_LOCATION C27
J 0
(2775 350);
DISPLAY 1.021277 (2775 350);
DISPLAY INVISIBLE (2775 350);
FORCEPROP 2 LAST $SEC 1
J 0
(2775 350);
DISPLAY 0.680851 (2775 350);
PAINT MONO (2775 350);
DISPLAY INVISIBLE (2775 350);
FORCEPROP 2 LAST CDS_SEC 1
J 0
(2775 350);
DISPLAY 1.021277 (2775 350);
DISPLAY INVISIBLE (2775 350);
FORCEPROP 1 LAST PATH I123
J 0
(2775 300);
DISPLAY 0.978723 (2775 300);
PAINT WHITE (2775 300);
DISPLAY INVISIBLE (2775 300);
FORCEADD VCC_CORE..1
(2725 475);
FORCEPROP 3 LASTPIN (2725 425) SIG_NAME P12V_S3_AUX_CPU0_NVDIMM\g
J 0
(2735 435);
DISPLAY 0.659574 (2735 435);
PAINT MONO (2735 435);
DISPLAY INVISIBLE (2735 435);
FORCEPROP 1 LAST HDL_POWER P12V_S3_AUX_CPU0_NVDIMM
J 1
(2725 525);
DISPLAY 1.148936 (2725 525);
PAINT GREEN (2725 525);
FORCEPROP 2 LAST CDS_LIB logical_power
J 0
(2725 475);
PAINT MONO (2725 475);
DISPLAY INVISIBLE (2725 475);
FORCEPROP 1 LAST PATH I124
J 0
(2775 500);
DISPLAY 0.872340 (2775 500);
PAINT AQUA (2775 500);
DISPLAY INVISIBLE (2775 500);
FORCEADD OFFPAGE..3
(825 2400);
FORCEPROP 2 LAST $XR1 91 
J 0
(1129 2400);
DISPLAY 0.638298 (1129 2400);
PAINT MONO (1129 2400);
FORCEPROP 2 LAST $XR0 24 
J 0
(1039 2400);
DISPLAY 0.638298 (1039 2400);
PAINT MONO (1039 2400);
FORCEPROP 2 LAST CDS_LIB standard
J 2
(825 2400);
DISPLAY INVISIBLE (825 2400);
FORCEPROP 1 LAST OFFPAGE TRUE
J 0
(1150 2275);
DISPLAY 0.872340 (1150 2275);
DISPLAY INVISIBLE (1150 2275);
FORCEPROP 1 LAST COMMENT_BODY TRUE
J 0
(775 2300);
DISPLAY 0.872340 (775 2300);
PAINT GREEN (775 2300);
DISPLAY INVISIBLE (775 2300);
FORCEPROP 2 LAST PATH I125
J 0
(1025 2475);
DISPLAY 1.021277 (1025 2475);
DISPLAY INVISIBLE (1025 2475);
FORCEADD TAP..1
(2750 2075);
FORCEPROP 3 LASTPIN (2700 2075) SIG_NAME M_E_CPU0_SB_DQS_DP<0>
J 0
(2710 2085);
DISPLAY 0.659574 (2710 2085);
PAINT MONO (2710 2085);
DISPLAY INVISIBLE (2710 2085);
FORCEPROP 1 LASTPIN (2700 2075) BN 0
J 0
(2688 2083);
DISPLAY 0.680851 (2688 2083);
PAINT GREEN (2688 2083);
FORCEPROP 2 LAST CDS_LIB standard
J 0
(2750 2075);
PAINT MONO (2750 2075);
DISPLAY INVISIBLE (2750 2075);
FORCEPROP 1 LAST BODY_TYPE PLUMBING
J 0
(2750 2125);
DISPLAY 0.872340 (2750 2125);
PAINT GREEN (2750 2125);
DISPLAY INVISIBLE (2750 2125);
FORCEPROP 1 LAST HDL_TAP TRUE
J 0
(3075 1950);
DISPLAY 0.872340 (3075 1950);
DISPLAY INVISIBLE (3075 1950);
FORCEPROP 1 LAST PATH I127
J 0
(2748 2075);
DISPLAY 0.872340 (2748 2075);
PAINT GREEN (2748 2075);
DISPLAY INVISIBLE (2748 2075);
FORCEADD TAP..1
(2750 2275);
FORCEPROP 3 LASTPIN (2700 2275) SIG_NAME M_E_CPU0_SB_DQS_DP<2>
J 0
(2710 2285);
DISPLAY 0.659574 (2710 2285);
PAINT MONO (2710 2285);
DISPLAY INVISIBLE (2710 2285);
FORCEPROP 1 LASTPIN (2700 2275) BN 2
J 0
(2688 2283);
DISPLAY 0.680851 (2688 2283);
PAINT GREEN (2688 2283);
FORCEPROP 2 LAST CDS_LIB standard
J 0
(2750 2275);
DISPLAY INVISIBLE (2750 2275);
FORCEPROP 1 LAST BODY_TYPE PLUMBING
J 0
(2750 2325);
DISPLAY 0.872340 (2750 2325);
PAINT GREEN (2750 2325);
DISPLAY INVISIBLE (2750 2325);
FORCEPROP 1 LAST HDL_TAP TRUE
J 0
(3075 2150);
DISPLAY 0.872340 (3075 2150);
DISPLAY INVISIBLE (3075 2150);
FORCEPROP 1 LAST PATH I128
J 0
(2748 2275);
DISPLAY 0.872340 (2748 2275);
PAINT GREEN (2748 2275);
DISPLAY INVISIBLE (2748 2275);
FORCEADD TAP..1
(2750 2175);
FORCEPROP 3 LASTPIN (2700 2175) SIG_NAME M_E_CPU0_SB_DQS_DP<1>
J 0
(2710 2185);
DISPLAY 0.659574 (2710 2185);
PAINT MONO (2710 2185);
DISPLAY INVISIBLE (2710 2185);
FORCEPROP 1 LASTPIN (2700 2175) BN 1
J 0
(2688 2183);
DISPLAY 0.680851 (2688 2183);
PAINT GREEN (2688 2183);
FORCEPROP 2 LAST CDS_LIB standard
J 0
(2750 2175);
DISPLAY INVISIBLE (2750 2175);
FORCEPROP 1 LAST BODY_TYPE PLUMBING
J 0
(2750 2225);
DISPLAY 0.872340 (2750 2225);
PAINT GREEN (2750 2225);
DISPLAY INVISIBLE (2750 2225);
FORCEPROP 1 LAST HDL_TAP TRUE
J 0
(3075 2050);
DISPLAY 0.872340 (3075 2050);
DISPLAY INVISIBLE (3075 2050);
FORCEPROP 1 LAST PATH I129
J 0
(2748 2175);
DISPLAY 0.872340 (2748 2175);
PAINT GREEN (2748 2175);
DISPLAY INVISIBLE (2748 2175);
FORCEADD OFFPAGE..3
R 2
(-2575 2200);
FORCEPROP 2 LAST $XR1 91 
J 0
(-2914 2200);
DISPLAY 0.638298 (-2914 2200);
PAINT MONO (-2914 2200);
FORCEPROP 2 LAST $XR0 24 
J 0
(-2824 2200);
DISPLAY 0.638298 (-2824 2200);
PAINT MONO (-2824 2200);
FORCEPROP 2 LAST CDS_LIB standard
J 0
(-2575 2200);
PAINT MONO (-2575 2200);
DISPLAY INVISIBLE (-2575 2200);
FORCEPROP 1 LAST OFFPAGE TRUE
J 2
(-2900 2075);
DISPLAY 0.872340 (-2900 2075);
DISPLAY INVISIBLE (-2900 2075);
FORCEPROP 1 LAST COMMENT_BODY TRUE
J 2
(-2525 2100);
DISPLAY 0.872340 (-2525 2100);
PAINT GREEN (-2525 2100);
DISPLAY INVISIBLE (-2525 2100);
FORCEPROP 2 LAST PATH I13
J 0
(-2525 2275);
DISPLAY 1.021277 (-2525 2275);
DISPLAY INVISIBLE (-2525 2275);
FORCEADD TAP..1
(2750 2375);
FORCEPROP 3 LASTPIN (2700 2375) SIG_NAME M_E_CPU0_SB_DQS_DP<3>
J 0
(2710 2385);
DISPLAY 0.659574 (2710 2385);
PAINT MONO (2710 2385);
DISPLAY INVISIBLE (2710 2385);
FORCEPROP 1 LASTPIN (2700 2375) BN 3
J 0
(2688 2383);
DISPLAY 0.680851 (2688 2383);
PAINT GREEN (2688 2383);
FORCEPROP 2 LAST CDS_LIB standard
J 0
(2750 2375);
PAINT MONO (2750 2375);
DISPLAY INVISIBLE (2750 2375);
FORCEPROP 1 LAST BODY_TYPE PLUMBING
J 0
(2750 2425);
DISPLAY 0.872340 (2750 2425);
PAINT GREEN (2750 2425);
DISPLAY INVISIBLE (2750 2425);
FORCEPROP 1 LAST HDL_TAP TRUE
J 0
(3075 2250);
DISPLAY 0.872340 (3075 2250);
DISPLAY INVISIBLE (3075 2250);
FORCEPROP 1 LAST PATH I130
J 0
(2748 2375);
DISPLAY 0.872340 (2748 2375);
PAINT GREEN (2748 2375);
DISPLAY INVISIBLE (2748 2375);
FORCEADD TAP..1
(2750 2475);
FORCEPROP 3 LASTPIN (2700 2475) SIG_NAME M_E_CPU0_SB_DQS_DP<4>
J 0
(2710 2485);
DISPLAY 0.659574 (2710 2485);
PAINT MONO (2710 2485);
DISPLAY INVISIBLE (2710 2485);
FORCEPROP 1 LASTPIN (2700 2475) BN 4
J 0
(2688 2483);
DISPLAY 0.680851 (2688 2483);
PAINT GREEN (2688 2483);
FORCEPROP 2 LAST CDS_LIB standard
J 0
(2750 2475);
PAINT MONO (2750 2475);
DISPLAY INVISIBLE (2750 2475);
FORCEPROP 1 LAST BODY_TYPE PLUMBING
J 0
(2750 2525);
DISPLAY 0.872340 (2750 2525);
PAINT GREEN (2750 2525);
DISPLAY INVISIBLE (2750 2525);
FORCEPROP 1 LAST HDL_TAP TRUE
J 0
(3075 2350);
DISPLAY 0.872340 (3075 2350);
DISPLAY INVISIBLE (3075 2350);
FORCEPROP 1 LAST PATH I131
J 0
(2748 2475);
DISPLAY 0.872340 (2748 2475);
PAINT GREEN (2748 2475);
DISPLAY INVISIBLE (2748 2475);
FORCEADD TAP..1
(2750 2575);
FORCEPROP 3 LASTPIN (2700 2575) SIG_NAME M_E_CPU0_SB_DQS_DP<5>
J 0
(2710 2585);
DISPLAY 0.659574 (2710 2585);
PAINT MONO (2710 2585);
DISPLAY INVISIBLE (2710 2585);
FORCEPROP 1 LASTPIN (2700 2575) BN 5
J 0
(2688 2583);
DISPLAY 0.680851 (2688 2583);
PAINT GREEN (2688 2583);
FORCEPROP 2 LAST CDS_LIB standard
J 0
(2750 2575);
DISPLAY INVISIBLE (2750 2575);
FORCEPROP 1 LAST BODY_TYPE PLUMBING
J 0
(2750 2625);
DISPLAY 0.872340 (2750 2625);
PAINT GREEN (2750 2625);
DISPLAY INVISIBLE (2750 2625);
FORCEPROP 1 LAST HDL_TAP TRUE
J 0
(3075 2450);
DISPLAY 0.872340 (3075 2450);
DISPLAY INVISIBLE (3075 2450);
FORCEPROP 1 LAST PATH I132
J 0
(2748 2575);
DISPLAY 0.872340 (2748 2575);
PAINT GREEN (2748 2575);
DISPLAY INVISIBLE (2748 2575);
FORCEADD TAP..1
(2750 2775);
FORCEPROP 3 LASTPIN (2700 2775) SIG_NAME M_E_CPU0_SB_DQS_DP<7>
J 0
(2710 2785);
DISPLAY 0.659574 (2710 2785);
PAINT MONO (2710 2785);
DISPLAY INVISIBLE (2710 2785);
FORCEPROP 1 LASTPIN (2700 2775) BN 7
J 0
(2688 2783);
DISPLAY 0.680851 (2688 2783);
PAINT GREEN (2688 2783);
FORCEPROP 2 LAST CDS_LIB standard
J 0
(2750 2775);
DISPLAY INVISIBLE (2750 2775);
FORCEPROP 1 LAST BODY_TYPE PLUMBING
J 0
(2750 2825);
DISPLAY 0.872340 (2750 2825);
PAINT GREEN (2750 2825);
DISPLAY INVISIBLE (2750 2825);
FORCEPROP 1 LAST HDL_TAP TRUE
J 0
(3075 2650);
DISPLAY 0.872340 (3075 2650);
DISPLAY INVISIBLE (3075 2650);
FORCEPROP 1 LAST PATH I133
J 0
(2748 2775);
DISPLAY 0.872340 (2748 2775);
PAINT GREEN (2748 2775);
DISPLAY INVISIBLE (2748 2775);
FORCEADD TAP..1
(2750 2675);
FORCEPROP 3 LASTPIN (2700 2675) SIG_NAME M_E_CPU0_SB_DQS_DP<6>
J 0
(2710 2685);
DISPLAY 0.659574 (2710 2685);
PAINT MONO (2710 2685);
DISPLAY INVISIBLE (2710 2685);
FORCEPROP 1 LASTPIN (2700 2675) BN 6
J 0
(2688 2683);
DISPLAY 0.680851 (2688 2683);
PAINT GREEN (2688 2683);
FORCEPROP 2 LAST CDS_LIB standard
J 0
(2750 2675);
DISPLAY INVISIBLE (2750 2675);
FORCEPROP 1 LAST BODY_TYPE PLUMBING
J 0
(2750 2725);
DISPLAY 0.872340 (2750 2725);
PAINT GREEN (2750 2725);
DISPLAY INVISIBLE (2750 2725);
FORCEPROP 1 LAST HDL_TAP TRUE
J 0
(3075 2550);
DISPLAY 0.872340 (3075 2550);
DISPLAY INVISIBLE (3075 2550);
FORCEPROP 1 LAST PATH I134
J 0
(2748 2675);
DISPLAY 0.872340 (2748 2675);
PAINT GREEN (2748 2675);
DISPLAY INVISIBLE (2748 2675);
FORCEADD TAP..1
(2750 2875);
FORCEPROP 3 LASTPIN (2700 2875) SIG_NAME M_E_CPU0_SB_DQS_DP<8>
J 0
(2710 2885);
DISPLAY 0.659574 (2710 2885);
PAINT MONO (2710 2885);
DISPLAY INVISIBLE (2710 2885);
FORCEPROP 1 LASTPIN (2700 2875) BN 8
J 0
(2688 2883);
DISPLAY 0.680851 (2688 2883);
PAINT GREEN (2688 2883);
FORCEPROP 2 LAST CDS_LIB standard
J 0
(2750 2875);
DISPLAY INVISIBLE (2750 2875);
FORCEPROP 1 LAST BODY_TYPE PLUMBING
J 0
(2750 2925);
DISPLAY 0.872340 (2750 2925);
PAINT GREEN (2750 2925);
DISPLAY INVISIBLE (2750 2925);
FORCEPROP 1 LAST HDL_TAP TRUE
J 0
(3075 2750);
DISPLAY 0.872340 (3075 2750);
DISPLAY INVISIBLE (3075 2750);
FORCEPROP 1 LAST PATH I135
J 0
(2748 2875);
DISPLAY 0.872340 (2748 2875);
PAINT GREEN (2748 2875);
DISPLAY INVISIBLE (2748 2875);
FORCEADD TAP..1
(2750 2975);
FORCEPROP 3 LASTPIN (2700 2975) SIG_NAME M_E_CPU0_SB_DQS_DP<9>
J 0
(2710 2985);
DISPLAY 0.659574 (2710 2985);
PAINT MONO (2710 2985);
DISPLAY INVISIBLE (2710 2985);
FORCEPROP 1 LASTPIN (2700 2975) BN 9
J 0
(2688 2983);
DISPLAY 0.680851 (2688 2983);
PAINT GREEN (2688 2983);
FORCEPROP 2 LAST CDS_LIB standard
J 0
(2750 2975);
DISPLAY INVISIBLE (2750 2975);
FORCEPROP 1 LAST BODY_TYPE PLUMBING
J 0
(2750 3025);
DISPLAY 0.872340 (2750 3025);
PAINT GREEN (2750 3025);
DISPLAY INVISIBLE (2750 3025);
FORCEPROP 1 LAST HDL_TAP TRUE
J 0
(3075 2850);
DISPLAY 0.872340 (3075 2850);
DISPLAY INVISIBLE (3075 2850);
FORCEPROP 1 LAST PATH I136
J 0
(2748 2975);
DISPLAY 0.872340 (2748 2975);
PAINT GREEN (2748 2975);
DISPLAY INVISIBLE (2748 2975);
FORCEADD TAP..1
(2750 3125);
FORCEPROP 3 LASTPIN (2700 3125) SIG_NAME M_E_CPU0_SA_DQS_DP<0>
J 0
(2710 3135);
DISPLAY 0.659574 (2710 3135);
PAINT MONO (2710 3135);
DISPLAY INVISIBLE (2710 3135);
FORCEPROP 1 LASTPIN (2700 3125) BN 0
J 0
(2688 3133);
DISPLAY 0.680851 (2688 3133);
PAINT GREEN (2688 3133);
FORCEPROP 2 LAST CDS_LIB standard
J 0
(2750 3125);
PAINT MONO (2750 3125);
DISPLAY INVISIBLE (2750 3125);
FORCEPROP 1 LAST BODY_TYPE PLUMBING
J 0
(2750 3175);
DISPLAY 0.872340 (2750 3175);
PAINT GREEN (2750 3175);
DISPLAY INVISIBLE (2750 3175);
FORCEPROP 1 LAST HDL_TAP TRUE
J 0
(3075 3000);
DISPLAY 0.872340 (3075 3000);
DISPLAY INVISIBLE (3075 3000);
FORCEPROP 1 LAST PATH I137
J 0
(2748 3125);
DISPLAY 0.872340 (2748 3125);
PAINT GREEN (2748 3125);
DISPLAY INVISIBLE (2748 3125);
FORCEADD TAP..1
(2750 3225);
FORCEPROP 3 LASTPIN (2700 3225) SIG_NAME M_E_CPU0_SA_DQS_DP<1>
J 0
(2710 3235);
DISPLAY 0.659574 (2710 3235);
PAINT MONO (2710 3235);
DISPLAY INVISIBLE (2710 3235);
FORCEPROP 1 LASTPIN (2700 3225) BN 1
J 0
(2688 3233);
DISPLAY 0.680851 (2688 3233);
PAINT GREEN (2688 3233);
FORCEPROP 2 LAST CDS_LIB standard
J 0
(2750 3225);
DISPLAY INVISIBLE (2750 3225);
FORCEPROP 1 LAST BODY_TYPE PLUMBING
J 0
(2750 3275);
DISPLAY 0.872340 (2750 3275);
PAINT GREEN (2750 3275);
DISPLAY INVISIBLE (2750 3275);
FORCEPROP 1 LAST HDL_TAP TRUE
J 0
(3075 3100);
DISPLAY 0.872340 (3075 3100);
DISPLAY INVISIBLE (3075 3100);
FORCEPROP 1 LAST PATH I138
J 0
(2748 3225);
DISPLAY 0.872340 (2748 3225);
PAINT GREEN (2748 3225);
DISPLAY INVISIBLE (2748 3225);
FORCEADD TAP..1
(2750 3325);
FORCEPROP 3 LASTPIN (2700 3325) SIG_NAME M_E_CPU0_SA_DQS_DP<2>
J 0
(2710 3335);
DISPLAY 0.659574 (2710 3335);
PAINT MONO (2710 3335);
DISPLAY INVISIBLE (2710 3335);
FORCEPROP 1 LASTPIN (2700 3325) BN 2
J 0
(2688 3333);
DISPLAY 0.680851 (2688 3333);
PAINT GREEN (2688 3333);
FORCEPROP 2 LAST CDS_LIB standard
J 0
(2750 3325);
DISPLAY INVISIBLE (2750 3325);
FORCEPROP 1 LAST BODY_TYPE PLUMBING
J 0
(2750 3375);
DISPLAY 0.872340 (2750 3375);
PAINT GREEN (2750 3375);
DISPLAY INVISIBLE (2750 3375);
FORCEPROP 1 LAST HDL_TAP TRUE
J 0
(3075 3200);
DISPLAY 0.872340 (3075 3200);
DISPLAY INVISIBLE (3075 3200);
FORCEPROP 1 LAST PATH I139
J 0
(2748 3325);
DISPLAY 0.872340 (2748 3325);
PAINT GREEN (2748 3325);
DISPLAY INVISIBLE (2748 3325);
FORCEADD VCC_CORE..1
(-2475 1900);
FORCEPROP 3 LASTPIN (-2475 1850) SIG_NAME P3V3_AUX\g
J 0
(-2465 1860);
DISPLAY 0.659574 (-2465 1860);
PAINT MONO (-2465 1860);
DISPLAY INVISIBLE (-2465 1860);
FORCEPROP 1 LAST HDL_POWER P3V3_AUX
J 1
(-2475 1950);
DISPLAY 1.148936 (-2475 1950);
PAINT GREEN (-2475 1950);
FORCEPROP 2 LAST CDS_LIB logical_power
J 0
(-2475 1900);
PAINT MONO (-2475 1900);
DISPLAY INVISIBLE (-2475 1900);
FORCEPROP 1 LAST PATH I14
J 0
(-2425 1925);
DISPLAY 0.872340 (-2425 1925);
PAINT AQUA (-2425 1925);
DISPLAY INVISIBLE (-2425 1925);
FORCEADD TAP..1
(2750 3425);
FORCEPROP 3 LASTPIN (2700 3425) SIG_NAME M_E_CPU0_SA_DQS_DP<3>
J 0
(2710 3435);
DISPLAY 0.659574 (2710 3435);
PAINT MONO (2710 3435);
DISPLAY INVISIBLE (2710 3435);
FORCEPROP 1 LASTPIN (2700 3425) BN 3
J 0
(2688 3433);
DISPLAY 0.680851 (2688 3433);
PAINT GREEN (2688 3433);
FORCEPROP 2 LAST CDS_LIB standard
J 0
(2750 3425);
PAINT MONO (2750 3425);
DISPLAY INVISIBLE (2750 3425);
FORCEPROP 1 LAST BODY_TYPE PLUMBING
J 0
(2750 3475);
DISPLAY 0.872340 (2750 3475);
PAINT GREEN (2750 3475);
DISPLAY INVISIBLE (2750 3475);
FORCEPROP 1 LAST HDL_TAP TRUE
J 0
(3075 3300);
DISPLAY 0.872340 (3075 3300);
DISPLAY INVISIBLE (3075 3300);
FORCEPROP 1 LAST PATH I140
J 0
(2748 3425);
DISPLAY 0.872340 (2748 3425);
PAINT GREEN (2748 3425);
DISPLAY INVISIBLE (2748 3425);
FORCEADD TAP..1
(2750 3525);
FORCEPROP 3 LASTPIN (2700 3525) SIG_NAME M_E_CPU0_SA_DQS_DP<4>
J 0
(2710 3535);
DISPLAY 0.659574 (2710 3535);
PAINT MONO (2710 3535);
DISPLAY INVISIBLE (2710 3535);
FORCEPROP 1 LASTPIN (2700 3525) BN 4
J 0
(2688 3533);
DISPLAY 0.680851 (2688 3533);
PAINT GREEN (2688 3533);
FORCEPROP 2 LAST CDS_LIB standard
J 0
(2750 3525);
PAINT MONO (2750 3525);
DISPLAY INVISIBLE (2750 3525);
FORCEPROP 1 LAST BODY_TYPE PLUMBING
J 0
(2750 3575);
DISPLAY 0.872340 (2750 3575);
PAINT GREEN (2750 3575);
DISPLAY INVISIBLE (2750 3575);
FORCEPROP 1 LAST HDL_TAP TRUE
J 0
(3075 3400);
DISPLAY 0.872340 (3075 3400);
DISPLAY INVISIBLE (3075 3400);
FORCEPROP 1 LAST PATH I141
J 0
(2748 3525);
DISPLAY 0.872340 (2748 3525);
PAINT GREEN (2748 3525);
DISPLAY INVISIBLE (2748 3525);
FORCEADD TAP..1
(2750 3625);
FORCEPROP 3 LASTPIN (2700 3625) SIG_NAME M_E_CPU0_SA_DQS_DP<5>
J 0
(2710 3635);
DISPLAY 0.659574 (2710 3635);
PAINT MONO (2710 3635);
DISPLAY INVISIBLE (2710 3635);
FORCEPROP 1 LASTPIN (2700 3625) BN 5
J 0
(2688 3633);
DISPLAY 0.680851 (2688 3633);
PAINT GREEN (2688 3633);
FORCEPROP 2 LAST CDS_LIB standard
J 0
(2750 3625);
DISPLAY INVISIBLE (2750 3625);
FORCEPROP 1 LAST BODY_TYPE PLUMBING
J 0
(2750 3675);
DISPLAY 0.872340 (2750 3675);
PAINT GREEN (2750 3675);
DISPLAY INVISIBLE (2750 3675);
FORCEPROP 1 LAST HDL_TAP TRUE
J 0
(3075 3500);
DISPLAY 0.872340 (3075 3500);
DISPLAY INVISIBLE (3075 3500);
FORCEPROP 1 LAST PATH I142
J 0
(2748 3625);
DISPLAY 0.872340 (2748 3625);
PAINT GREEN (2748 3625);
DISPLAY INVISIBLE (2748 3625);
FORCEADD TAP..1
(2750 3725);
FORCEPROP 3 LASTPIN (2700 3725) SIG_NAME M_E_CPU0_SA_DQS_DP<6>
J 0
(2710 3735);
DISPLAY 0.659574 (2710 3735);
PAINT MONO (2710 3735);
DISPLAY INVISIBLE (2710 3735);
FORCEPROP 1 LASTPIN (2700 3725) BN 6
J 0
(2688 3733);
DISPLAY 0.680851 (2688 3733);
PAINT GREEN (2688 3733);
FORCEPROP 2 LAST CDS_LIB standard
J 0
(2750 3725);
DISPLAY INVISIBLE (2750 3725);
FORCEPROP 1 LAST BODY_TYPE PLUMBING
J 0
(2750 3775);
DISPLAY 0.872340 (2750 3775);
PAINT GREEN (2750 3775);
DISPLAY INVISIBLE (2750 3775);
FORCEPROP 1 LAST HDL_TAP TRUE
J 0
(3075 3600);
DISPLAY 0.872340 (3075 3600);
DISPLAY INVISIBLE (3075 3600);
FORCEPROP 1 LAST PATH I143
J 0
(2748 3725);
DISPLAY 0.872340 (2748 3725);
PAINT GREEN (2748 3725);
DISPLAY INVISIBLE (2748 3725);
FORCEADD UNIVERSAL_GND..1
(3350 -225);
FORCEPROP 3 LASTPIN (3350 -175) SIG_NAME GND\g
J 0
(3360 -165);
DISPLAY 0.659574 (3360 -165);
PAINT MONO (3360 -165);
DISPLAY INVISIBLE (3360 -165);
FORCEPROP 2 LAST CDS_LIB logical_power
J 0
(3350 -225);
PAINT MONO (3350 -225);
DISPLAY INVISIBLE (3350 -225);
FORCEPROP 1 LAST HDL_POWER GND
J 1
(3375 -300);
DISPLAY 0.872340 (3375 -300);
PAINT GREEN (3375 -300);
DISPLAY INVISIBLE (3375 -300);
FORCEPROP 1 LAST PATH I144
J 0
(3425 -225);
DISPLAY 0.872340 (3425 -225);
PAINT AQUA (3425 -225);
DISPLAY INVISIBLE (3425 -225);
FORCEADD Q_CAP..1
(3350 150);
FORCEPROP 1 LAST PART_NUMBER CH6103KEA00
J 0
(3400 0);
DISPLAY 0.978723 (3400 0);
DISPLAY INVISIBLE (3400 0);
FORCEPROP 1 LAST PACK_TYPE C0805
J 0
(3400 -50);
DISPLAY 0.978723 (3400 -50);
FORCEPROP 1 LAST TOLERANCE 10%
J 0
(3400 100);
DISPLAY 0.978723 (3400 100);
FORCEPROP 1 LAST VOLTAGE 16V
J 0
(3400 150);
DISPLAY 0.978723 (3400 150);
FORCEPROP 1 LAST VALUE 10UF
J 0
(3400 200);
DISPLAY 0.978723 (3400 200);
FORCEPROP 1 LAST MATERIAL X6S
J 0
(3400 50);
DISPLAY 0.978723 (3400 50);
FORCEPROP 1 LAST $LOCATION C28
J 0
(3400 250);
DISPLAY 0.978723 (3400 250);
FORCEPROP 1 LASTPIN (3350 250) $PN 1
J 0
(3360 230);
DISPLAY 0.787234 (3360 230);
FORCEPROP 1 LASTPIN (3350 50) $PN 2
J 0
(3360 30);
DISPLAY 0.787234 (3360 30);
FORCEPROP 2 LAST CDS_LIB pure_quanta
J 0
(3350 150);
PAINT MONO (3350 150);
DISPLAY INVISIBLE (3350 150);
FORCEPROP 2 LAST CDS_LOCATION C28
J 0
(3400 350);
DISPLAY 1.021277 (3400 350);
DISPLAY INVISIBLE (3400 350);
FORCEPROP 2 LAST $SEC 1
J 0
(3400 350);
DISPLAY 0.680851 (3400 350);
PAINT MONO (3400 350);
DISPLAY INVISIBLE (3400 350);
FORCEPROP 2 LAST CDS_SEC 1
J 0
(3400 350);
DISPLAY 1.021277 (3400 350);
DISPLAY INVISIBLE (3400 350);
FORCEPROP 1 LAST PATH I145
J 0
(3400 300);
DISPLAY 0.978723 (3400 300);
PAINT WHITE (3400 300);
DISPLAY INVISIBLE (3400 300);
FORCEADD UNIVERSAL_GND..1
(4425 325);
FORCEPROP 3 LASTPIN (4425 375) SIG_NAME GND\g
J 0
(4435 385);
DISPLAY 0.659574 (4435 385);
PAINT MONO (4435 385);
DISPLAY INVISIBLE (4435 385);
FORCEPROP 2 LAST CDS_LIB logical_power
J 0
(4425 325);
PAINT MONO (4425 325);
DISPLAY INVISIBLE (4425 325);
FORCEPROP 1 LAST HDL_POWER GND
J 1
(4450 250);
DISPLAY 0.872340 (4450 250);
PAINT GREEN (4450 250);
DISPLAY INVISIBLE (4450 250);
FORCEPROP 1 LAST PATH I146
J 0
(4500 325);
DISPLAY 0.872340 (4500 325);
PAINT AQUA (4500 325);
DISPLAY INVISIBLE (4500 325);
FORCEADD SCONN288_ADR50017P130CC..3
(5275 2400);
FORCEPROP 1 LAST PART_NUMBER DFHST8FS461
J 0
(4820 4324);
DISPLAY 0.723404 (4820 4324);
PAINT GREEN (4820 4324);
DISPLAY INVISIBLE (4820 4324);
FORCEPROP 1 LAST MATERIAL IO
J 0
(4820 4197);
DISPLAY 0.723404 (4820 4197);
PAINT GREEN (4820 4197);
FORCEPROP 2 LAST PART_TYPE SMLF
J 0
(4825 4475);
DISPLAY 1.021277 (4825 4475);
FORCEPROP 2 LAST VALUE SCONN288_ADR50017-P130CC
J 0
(4825 4425);
DISPLAY 1.021277 (4825 4425);
FORCEPROP 1 LAST $LOCATION J9
J 0
(4825 4375);
DISPLAY 0.723404 (4825 4375);
PAINT GREEN (4825 4375);
FORCEPROP 0 LASTPIN (5875 775) $PN G1
J 0
(5885 785);
DISPLAY 0.680851 (5885 785);
PAINT MONO (5885 785);
FORCEPROP 0 LASTPIN (5875 725) $PN G2
J 0
(5885 735);
DISPLAY 0.680851 (5885 735);
PAINT MONO (5885 735);
FORCEPROP 0 LASTPIN (5875 675) $PN G3
J 0
(5885 685);
DISPLAY 0.680851 (5885 685);
PAINT MONO (5885 685);
FORCEPROP 0 LASTPIN (4675 3925) $PN 1
J 2
(4665 3935);
DISPLAY 0.680851 (4665 3935);
PAINT MONO (4665 3935);
FORCEPROP 0 LASTPIN (4675 3975) $PN 145
J 2
(4665 3985);
DISPLAY 0.680851 (4665 3985);
PAINT MONO (4665 3985);
FORCEPROP 0 LASTPIN (4675 4025) $PN 146
J 2
(4665 4035);
DISPLAY 0.680851 (4665 4035);
PAINT MONO (4665 4035);
FORCEPROP 0 LASTPIN (5875 875) $PN 6
J 0
(5885 885);
DISPLAY 0.680851 (5885 885);
PAINT MONO (5885 885);
FORCEPROP 0 LASTPIN (5875 925) $PN 8
J 0
(5885 935);
DISPLAY 0.680851 (5885 935);
PAINT MONO (5885 935);
FORCEPROP 0 LASTPIN (5875 975) $PN 10
J 0
(5885 985);
DISPLAY 0.680851 (5885 985);
PAINT MONO (5885 985);
FORCEPROP 0 LASTPIN (5875 1025) $PN 13
J 0
(5885 1035);
DISPLAY 0.680851 (5885 1035);
PAINT MONO (5885 1035);
FORCEPROP 0 LASTPIN (5875 1075) $PN 15
J 0
(5885 1085);
DISPLAY 0.680851 (5885 1085);
PAINT MONO (5885 1085);
FORCEPROP 0 LASTPIN (5875 1125) $PN 17
J 0
(5885 1135);
DISPLAY 0.680851 (5885 1135);
PAINT MONO (5885 1135);
FORCEPROP 0 LASTPIN (5875 1175) $PN 19
J 0
(5885 1185);
DISPLAY 0.680851 (5885 1185);
PAINT MONO (5885 1185);
FORCEPROP 0 LASTPIN (5875 1225) $PN 21
J 0
(5885 1235);
DISPLAY 0.680851 (5885 1235);
PAINT MONO (5885 1235);
FORCEPROP 0 LASTPIN (5875 1275) $PN 24
J 0
(5885 1285);
DISPLAY 0.680851 (5885 1285);
PAINT MONO (5885 1285);
FORCEPROP 0 LASTPIN (5875 1325) $PN 26
J 0
(5885 1335);
DISPLAY 0.680851 (5885 1335);
PAINT MONO (5885 1335);
FORCEPROP 0 LASTPIN (5875 1375) $PN 28
J 0
(5885 1385);
DISPLAY 0.680851 (5885 1385);
PAINT MONO (5885 1385);
FORCEPROP 0 LASTPIN (5875 1425) $PN 30
J 0
(5885 1435);
DISPLAY 0.680851 (5885 1435);
PAINT MONO (5885 1435);
FORCEPROP 0 LASTPIN (5875 1475) $PN 32
J 0
(5885 1485);
DISPLAY 0.680851 (5885 1485);
PAINT MONO (5885 1485);
FORCEPROP 0 LASTPIN (5875 1525) $PN 35
J 0
(5885 1535);
DISPLAY 0.680851 (5885 1535);
PAINT MONO (5885 1535);
FORCEPROP 0 LASTPIN (5875 1575) $PN 37
J 0
(5885 1585);
DISPLAY 0.680851 (5885 1585);
PAINT MONO (5885 1585);
FORCEPROP 0 LASTPIN (5875 1625) $PN 39
J 0
(5885 1635);
DISPLAY 0.680851 (5885 1635);
PAINT MONO (5885 1635);
FORCEPROP 0 LASTPIN (5875 1675) $PN 41
J 0
(5885 1685);
DISPLAY 0.680851 (5885 1685);
PAINT MONO (5885 1685);
FORCEPROP 0 LASTPIN (5875 1725) $PN 43
J 0
(5885 1735);
DISPLAY 0.680851 (5885 1735);
PAINT MONO (5885 1735);
FORCEPROP 0 LASTPIN (5875 1775) $PN 46
J 0
(5885 1785);
DISPLAY 0.680851 (5885 1785);
PAINT MONO (5885 1785);
FORCEPROP 0 LASTPIN (5875 1825) $PN 48
J 0
(5885 1835);
DISPLAY 0.680851 (5885 1835);
PAINT MONO (5885 1835);
FORCEPROP 0 LASTPIN (5875 1875) $PN 50
J 0
(5885 1885);
DISPLAY 0.680851 (5885 1885);
PAINT MONO (5885 1885);
FORCEPROP 0 LASTPIN (5875 1925) $PN 52
J 0
(5885 1935);
DISPLAY 0.680851 (5885 1935);
PAINT MONO (5885 1935);
FORCEPROP 0 LASTPIN (5875 1975) $PN 54
J 0
(5885 1985);
DISPLAY 0.680851 (5885 1985);
PAINT MONO (5885 1985);
FORCEPROP 0 LASTPIN (5875 2025) $PN 57
J 0
(5885 2035);
DISPLAY 0.680851 (5885 2035);
PAINT MONO (5885 2035);
FORCEPROP 0 LASTPIN (5875 2075) $PN 59
J 0
(5885 2085);
DISPLAY 0.680851 (5885 2085);
PAINT MONO (5885 2085);
FORCEPROP 0 LASTPIN (5875 2125) $PN 61
J 0
(5885 2135);
DISPLAY 0.680851 (5885 2135);
PAINT MONO (5885 2135);
FORCEPROP 0 LASTPIN (5875 2175) $PN 63
J 0
(5885 2185);
DISPLAY 0.680851 (5885 2185);
PAINT MONO (5885 2185);
FORCEPROP 0 LASTPIN (5875 2225) $PN 65
J 0
(5885 2235);
DISPLAY 0.680851 (5885 2235);
PAINT MONO (5885 2235);
FORCEPROP 0 LASTPIN (5875 2275) $PN 67
J 0
(5885 2285);
DISPLAY 0.680851 (5885 2285);
PAINT MONO (5885 2285);
FORCEPROP 0 LASTPIN (5875 2325) $PN 69
J 0
(5885 2335);
DISPLAY 0.680851 (5885 2335);
PAINT MONO (5885 2335);
FORCEPROP 0 LASTPIN (5875 2375) $PN 71
J 0
(5885 2385);
DISPLAY 0.680851 (5885 2385);
PAINT MONO (5885 2385);
FORCEPROP 0 LASTPIN (5875 2425) $PN 73
J 0
(5885 2435);
DISPLAY 0.680851 (5885 2435);
PAINT MONO (5885 2435);
FORCEPROP 0 LASTPIN (5875 2475) $PN 75
J 0
(5885 2485);
DISPLAY 0.680851 (5885 2485);
PAINT MONO (5885 2485);
FORCEPROP 0 LASTPIN (5875 2525) $PN 77
J 0
(5885 2535);
DISPLAY 0.680851 (5885 2535);
PAINT MONO (5885 2535);
FORCEPROP 0 LASTPIN (5875 2575) $PN 79
J 0
(5885 2585);
DISPLAY 0.680851 (5885 2585);
PAINT MONO (5885 2585);
FORCEPROP 0 LASTPIN (5875 2625) $PN 81
J 0
(5885 2635);
DISPLAY 0.680851 (5885 2635);
PAINT MONO (5885 2635);
FORCEPROP 0 LASTPIN (5875 2675) $PN 83
J 0
(5885 2685);
DISPLAY 0.680851 (5885 2685);
PAINT MONO (5885 2685);
FORCEPROP 0 LASTPIN (5875 2725) $PN 85
J 0
(5885 2735);
DISPLAY 0.680851 (5885 2735);
PAINT MONO (5885 2735);
FORCEPROP 0 LASTPIN (5875 2775) $PN 88
J 0
(5885 2785);
DISPLAY 0.680851 (5885 2785);
PAINT MONO (5885 2785);
FORCEPROP 0 LASTPIN (5875 2825) $PN 90
J 0
(5885 2835);
DISPLAY 0.680851 (5885 2835);
PAINT MONO (5885 2835);
FORCEPROP 0 LASTPIN (5875 2875) $PN 92
J 0
(5885 2885);
DISPLAY 0.680851 (5885 2885);
PAINT MONO (5885 2885);
FORCEPROP 0 LASTPIN (5875 2925) $PN 95
J 0
(5885 2935);
DISPLAY 0.680851 (5885 2935);
PAINT MONO (5885 2935);
FORCEPROP 0 LASTPIN (5875 2975) $PN 97
J 0
(5885 2985);
DISPLAY 0.680851 (5885 2985);
PAINT MONO (5885 2985);
FORCEPROP 0 LASTPIN (5875 3025) $PN 99
J 0
(5885 3035);
DISPLAY 0.680851 (5885 3035);
PAINT MONO (5885 3035);
FORCEPROP 0 LASTPIN (5875 3075) $PN 101
J 0
(5885 3085);
DISPLAY 0.680851 (5885 3085);
PAINT MONO (5885 3085);
FORCEPROP 0 LASTPIN (5875 3125) $PN 103
J 0
(5885 3135);
DISPLAY 0.680851 (5885 3135);
PAINT MONO (5885 3135);
FORCEPROP 0 LASTPIN (5875 3175) $PN 106
J 0
(5885 3185);
DISPLAY 0.680851 (5885 3185);
PAINT MONO (5885 3185);
FORCEPROP 0 LASTPIN (5875 3225) $PN 108
J 0
(5885 3235);
DISPLAY 0.680851 (5885 3235);
PAINT MONO (5885 3235);
FORCEPROP 0 LASTPIN (5875 3275) $PN 110
J 0
(5885 3285);
DISPLAY 0.680851 (5885 3285);
PAINT MONO (5885 3285);
FORCEPROP 0 LASTPIN (5875 3325) $PN 112
J 0
(5885 3335);
DISPLAY 0.680851 (5885 3335);
PAINT MONO (5885 3335);
FORCEPROP 0 LASTPIN (5875 3375) $PN 114
J 0
(5885 3385);
DISPLAY 0.680851 (5885 3385);
PAINT MONO (5885 3385);
FORCEPROP 0 LASTPIN (5875 3425) $PN 117
J 0
(5885 3435);
DISPLAY 0.680851 (5885 3435);
PAINT MONO (5885 3435);
FORCEPROP 0 LASTPIN (5875 3475) $PN 119
J 0
(5885 3485);
DISPLAY 0.680851 (5885 3485);
PAINT MONO (5885 3485);
FORCEPROP 0 LASTPIN (5875 3525) $PN 121
J 0
(5885 3535);
DISPLAY 0.680851 (5885 3535);
PAINT MONO (5885 3535);
FORCEPROP 0 LASTPIN (5875 3575) $PN 123
J 0
(5885 3585);
DISPLAY 0.680851 (5885 3585);
PAINT MONO (5885 3585);
FORCEPROP 0 LASTPIN (5875 3625) $PN 125
J 0
(5885 3635);
DISPLAY 0.680851 (5885 3635);
PAINT MONO (5885 3635);
FORCEPROP 0 LASTPIN (5875 3675) $PN 128
J 0
(5885 3685);
DISPLAY 0.680851 (5885 3685);
PAINT MONO (5885 3685);
FORCEPROP 0 LASTPIN (5875 3725) $PN 130
J 0
(5885 3735);
DISPLAY 0.680851 (5885 3735);
PAINT MONO (5885 3735);
FORCEPROP 0 LASTPIN (5875 3775) $PN 132
J 0
(5885 3785);
DISPLAY 0.680851 (5885 3785);
PAINT MONO (5885 3785);
FORCEPROP 0 LASTPIN (5875 3825) $PN 134
J 0
(5885 3835);
DISPLAY 0.680851 (5885 3835);
PAINT MONO (5885 3835);
FORCEPROP 0 LASTPIN (5875 3875) $PN 136
J 0
(5885 3885);
DISPLAY 0.680851 (5885 3885);
PAINT MONO (5885 3885);
FORCEPROP 0 LASTPIN (5875 3925) $PN 139
J 0
(5885 3935);
DISPLAY 0.680851 (5885 3935);
PAINT MONO (5885 3935);
FORCEPROP 0 LASTPIN (5875 3975) $PN 141
J 0
(5885 3985);
DISPLAY 0.680851 (5885 3985);
PAINT MONO (5885 3985);
FORCEPROP 0 LASTPIN (5875 4025) $PN 143
J 0
(5885 4035);
DISPLAY 0.680851 (5885 4035);
PAINT MONO (5885 4035);
FORCEPROP 0 LASTPIN (4675 775) $PN 151
J 2
(4665 785);
DISPLAY 0.680851 (4665 785);
PAINT MONO (4665 785);
FORCEPROP 0 LASTPIN (4675 825) $PN 153
J 2
(4665 835);
DISPLAY 0.680851 (4665 835);
PAINT MONO (4665 835);
FORCEPROP 0 LASTPIN (4675 875) $PN 155
J 2
(4665 885);
DISPLAY 0.680851 (4665 885);
PAINT MONO (4665 885);
FORCEPROP 0 LASTPIN (4675 925) $PN 158
J 2
(4665 935);
DISPLAY 0.680851 (4665 935);
PAINT MONO (4665 935);
FORCEPROP 0 LASTPIN (4675 975) $PN 160
J 2
(4665 985);
DISPLAY 0.680851 (4665 985);
PAINT MONO (4665 985);
FORCEPROP 0 LASTPIN (4675 1025) $PN 162
J 2
(4665 1035);
DISPLAY 0.680851 (4665 1035);
PAINT MONO (4665 1035);
FORCEPROP 0 LASTPIN (4675 1075) $PN 164
J 2
(4665 1085);
DISPLAY 0.680851 (4665 1085);
PAINT MONO (4665 1085);
FORCEPROP 0 LASTPIN (4675 1125) $PN 166
J 2
(4665 1135);
DISPLAY 0.680851 (4665 1135);
PAINT MONO (4665 1135);
FORCEPROP 0 LASTPIN (4675 1175) $PN 169
J 2
(4665 1185);
DISPLAY 0.680851 (4665 1185);
PAINT MONO (4665 1185);
FORCEPROP 0 LASTPIN (4675 1225) $PN 171
J 2
(4665 1235);
DISPLAY 0.680851 (4665 1235);
PAINT MONO (4665 1235);
FORCEPROP 0 LASTPIN (4675 1275) $PN 173
J 2
(4665 1285);
DISPLAY 0.680851 (4665 1285);
PAINT MONO (4665 1285);
FORCEPROP 0 LASTPIN (4675 1325) $PN 175
J 2
(4665 1335);
DISPLAY 0.680851 (4665 1335);
PAINT MONO (4665 1335);
FORCEPROP 0 LASTPIN (4675 1375) $PN 177
J 2
(4665 1385);
DISPLAY 0.680851 (4665 1385);
PAINT MONO (4665 1385);
FORCEPROP 0 LASTPIN (4675 1425) $PN 180
J 2
(4665 1435);
DISPLAY 0.680851 (4665 1435);
PAINT MONO (4665 1435);
FORCEPROP 0 LASTPIN (4675 1475) $PN 182
J 2
(4665 1485);
DISPLAY 0.680851 (4665 1485);
PAINT MONO (4665 1485);
FORCEPROP 0 LASTPIN (4675 1525) $PN 184
J 2
(4665 1535);
DISPLAY 0.680851 (4665 1535);
PAINT MONO (4665 1535);
FORCEPROP 0 LASTPIN (4675 1575) $PN 186
J 2
(4665 1585);
DISPLAY 0.680851 (4665 1585);
PAINT MONO (4665 1585);
FORCEPROP 0 LASTPIN (4675 1625) $PN 188
J 2
(4665 1635);
DISPLAY 0.680851 (4665 1635);
PAINT MONO (4665 1635);
FORCEPROP 0 LASTPIN (4675 1675) $PN 191
J 2
(4665 1685);
DISPLAY 0.680851 (4665 1685);
PAINT MONO (4665 1685);
FORCEPROP 0 LASTPIN (4675 1725) $PN 193
J 2
(4665 1735);
DISPLAY 0.680851 (4665 1735);
PAINT MONO (4665 1735);
FORCEPROP 0 LASTPIN (4675 1775) $PN 195
J 2
(4665 1785);
DISPLAY 0.680851 (4665 1785);
PAINT MONO (4665 1785);
FORCEPROP 0 LASTPIN (4675 1825) $PN 197
J 2
(4665 1835);
DISPLAY 0.680851 (4665 1835);
PAINT MONO (4665 1835);
FORCEPROP 0 LASTPIN (4675 1875) $PN 199
J 2
(4665 1885);
DISPLAY 0.680851 (4665 1885);
PAINT MONO (4665 1885);
FORCEPROP 0 LASTPIN (4675 1925) $PN 202
J 2
(4665 1935);
DISPLAY 0.680851 (4665 1935);
PAINT MONO (4665 1935);
FORCEPROP 0 LASTPIN (4675 1975) $PN 204
J 2
(4665 1985);
DISPLAY 0.680851 (4665 1985);
PAINT MONO (4665 1985);
FORCEPROP 0 LASTPIN (4675 2025) $PN 206
J 2
(4665 2035);
DISPLAY 0.680851 (4665 2035);
PAINT MONO (4665 2035);
FORCEPROP 0 LASTPIN (4675 2075) $PN 208
J 2
(4665 2085);
DISPLAY 0.680851 (4665 2085);
PAINT MONO (4665 2085);
FORCEPROP 0 LASTPIN (4675 2125) $PN 210
J 2
(4665 2135);
DISPLAY 0.680851 (4665 2135);
PAINT MONO (4665 2135);
FORCEPROP 0 LASTPIN (4675 2175) $PN 212
J 2
(4665 2185);
DISPLAY 0.680851 (4665 2185);
PAINT MONO (4665 2185);
FORCEPROP 0 LASTPIN (4675 2225) $PN 214
J 2
(4665 2235);
DISPLAY 0.680851 (4665 2235);
PAINT MONO (4665 2235);
FORCEPROP 0 LASTPIN (4675 2275) $PN 216
J 2
(4665 2285);
DISPLAY 0.680851 (4665 2285);
PAINT MONO (4665 2285);
FORCEPROP 0 LASTPIN (4675 2325) $PN 219
J 2
(4665 2335);
DISPLAY 0.680851 (4665 2335);
PAINT MONO (4665 2335);
FORCEPROP 0 LASTPIN (4675 2375) $PN 222
J 2
(4665 2385);
DISPLAY 0.680851 (4665 2385);
PAINT MONO (4665 2385);
FORCEPROP 0 LASTPIN (4675 2425) $PN 224
J 2
(4665 2435);
DISPLAY 0.680851 (4665 2435);
PAINT MONO (4665 2435);
FORCEPROP 0 LASTPIN (4675 2475) $PN 226
J 2
(4665 2485);
DISPLAY 0.680851 (4665 2485);
PAINT MONO (4665 2485);
FORCEPROP 0 LASTPIN (4675 2525) $PN 228
J 2
(4665 2535);
DISPLAY 0.680851 (4665 2535);
PAINT MONO (4665 2535);
FORCEPROP 0 LASTPIN (4675 2575) $PN 230
J 2
(4665 2585);
DISPLAY 0.680851 (4665 2585);
PAINT MONO (4665 2585);
FORCEPROP 0 LASTPIN (4675 2625) $PN 233
J 2
(4665 2635);
DISPLAY 0.680851 (4665 2635);
PAINT MONO (4665 2635);
FORCEPROP 0 LASTPIN (4675 2675) $PN 235
J 2
(4665 2685);
DISPLAY 0.680851 (4665 2685);
PAINT MONO (4665 2685);
FORCEPROP 0 LASTPIN (4675 2725) $PN 237
J 2
(4665 2735);
DISPLAY 0.680851 (4665 2735);
PAINT MONO (4665 2735);
FORCEPROP 0 LASTPIN (4675 2775) $PN 240
J 2
(4665 2785);
DISPLAY 0.680851 (4665 2785);
PAINT MONO (4665 2785);
FORCEPROP 0 LASTPIN (4675 2825) $PN 242
J 2
(4665 2835);
DISPLAY 0.680851 (4665 2835);
PAINT MONO (4665 2835);
FORCEPROP 0 LASTPIN (4675 2875) $PN 244
J 2
(4665 2885);
DISPLAY 0.680851 (4665 2885);
PAINT MONO (4665 2885);
FORCEPROP 0 LASTPIN (4675 2925) $PN 246
J 2
(4665 2935);
DISPLAY 0.680851 (4665 2935);
PAINT MONO (4665 2935);
FORCEPROP 0 LASTPIN (4675 2975) $PN 248
J 2
(4665 2985);
DISPLAY 0.680851 (4665 2985);
PAINT MONO (4665 2985);
FORCEPROP 0 LASTPIN (4675 3025) $PN 251
J 2
(4665 3035);
DISPLAY 0.680851 (4665 3035);
PAINT MONO (4665 3035);
FORCEPROP 0 LASTPIN (4675 3075) $PN 253
J 2
(4665 3085);
DISPLAY 0.680851 (4665 3085);
PAINT MONO (4665 3085);
FORCEPROP 0 LASTPIN (4675 3125) $PN 255
J 2
(4665 3135);
DISPLAY 0.680851 (4665 3135);
PAINT MONO (4665 3135);
FORCEPROP 0 LASTPIN (4675 3175) $PN 257
J 2
(4665 3185);
DISPLAY 0.680851 (4665 3185);
PAINT MONO (4665 3185);
FORCEPROP 0 LASTPIN (4675 3225) $PN 259
J 2
(4665 3235);
DISPLAY 0.680851 (4665 3235);
PAINT MONO (4665 3235);
FORCEPROP 0 LASTPIN (4675 3275) $PN 262
J 2
(4665 3285);
DISPLAY 0.680851 (4665 3285);
PAINT MONO (4665 3285);
FORCEPROP 0 LASTPIN (4675 3325) $PN 264
J 2
(4665 3335);
DISPLAY 0.680851 (4665 3335);
PAINT MONO (4665 3335);
FORCEPROP 0 LASTPIN (4675 3375) $PN 266
J 2
(4665 3385);
DISPLAY 0.680851 (4665 3385);
PAINT MONO (4665 3385);
FORCEPROP 0 LASTPIN (4675 3425) $PN 268
J 2
(4665 3435);
DISPLAY 0.680851 (4665 3435);
PAINT MONO (4665 3435);
FORCEPROP 0 LASTPIN (4675 3475) $PN 270
J 2
(4665 3485);
DISPLAY 0.680851 (4665 3485);
PAINT MONO (4665 3485);
FORCEPROP 0 LASTPIN (4675 3525) $PN 273
J 2
(4665 3535);
DISPLAY 0.680851 (4665 3535);
PAINT MONO (4665 3535);
FORCEPROP 0 LASTPIN (4675 3575) $PN 275
J 2
(4665 3585);
DISPLAY 0.680851 (4665 3585);
PAINT MONO (4665 3585);
FORCEPROP 0 LASTPIN (4675 3625) $PN 277
J 2
(4665 3635);
DISPLAY 0.680851 (4665 3635);
PAINT MONO (4665 3635);
FORCEPROP 0 LASTPIN (4675 3675) $PN 279
J 2
(4665 3685);
DISPLAY 0.680851 (4665 3685);
PAINT MONO (4665 3685);
FORCEPROP 0 LASTPIN (4675 3725) $PN 281
J 2
(4665 3735);
DISPLAY 0.680851 (4665 3735);
PAINT MONO (4665 3735);
FORCEPROP 0 LASTPIN (4675 3775) $PN 284
J 2
(4665 3785);
DISPLAY 0.680851 (4665 3785);
PAINT MONO (4665 3785);
FORCEPROP 0 LASTPIN (4675 3825) $PN 286
J 2
(4665 3835);
DISPLAY 0.680851 (4665 3835);
PAINT MONO (4665 3835);
FORCEPROP 0 LASTPIN (4675 3875) $PN 288
J 2
(4665 3885);
DISPLAY 0.680851 (4665 3885);
PAINT MONO (4665 3885);
FORCEPROP 1 LAST NEEDS_NO_SIZE TRUE
J 0
(5275 2400);
DISPLAY 0.723404 (5275 2400);
PAINT GREEN (5275 2400);
DISPLAY INVISIBLE (5275 2400);
FORCEPROP 1 LAST CDS_LMAN_SYM_OUTLINE -450,1775,450,-1775
J 0
(5275 2400);
DISPLAY 0.468085 (5275 2400);
PAINT GREEN (5275 2400);
DISPLAY INVISIBLE (5275 2400);
FORCEPROP 2 LAST CDS_LIB pure_quanta
J 0
(5275 2400);
DISPLAY INVISIBLE (5275 2400);
FORCEPROP 2 LAST CDS_LOCATION J9
J 0
(4825 4525);
DISPLAY 1.021277 (4825 4525);
DISPLAY INVISIBLE (4825 4525);
FORCEPROP 0 LAST $SEC 3
J 0
(4825 4525);
DISPLAY 0.680851 (4825 4525);
PAINT MONO (4825 4525);
DISPLAY INVISIBLE (4825 4525);
FORCEPROP 2 LAST CDS_SEC 3
J 0
(4825 4525);
DISPLAY 1.021277 (4825 4525);
DISPLAY INVISIBLE (4825 4525);
FORCEPROP 1 LAST PATH I147
J 0
(5275 2400);
DISPLAY 0.723404 (5275 2400);
PAINT GREEN (5275 2400);
DISPLAY INVISIBLE (5275 2400);
FORCEADD TAP..1
(2925 2025);
FORCEPROP 3 LASTPIN (2875 2025) SIG_NAME M_E_CPU0_SB_DQS_DN<0>
J 0
(2885 2035);
DISPLAY 0.659574 (2885 2035);
PAINT MONO (2885 2035);
DISPLAY INVISIBLE (2885 2035);
FORCEPROP 1 LASTPIN (2875 2025) BN 0
J 0
(2863 2033);
DISPLAY 0.680851 (2863 2033);
PAINT GREEN (2863 2033);
FORCEPROP 2 LAST CDS_LIB standard
J 0
(2925 2025);
PAINT MONO (2925 2025);
DISPLAY INVISIBLE (2925 2025);
FORCEPROP 1 LAST BODY_TYPE PLUMBING
J 0
(2925 2075);
DISPLAY 0.872340 (2925 2075);
PAINT GREEN (2925 2075);
DISPLAY INVISIBLE (2925 2075);
FORCEPROP 1 LAST HDL_TAP TRUE
J 0
(3250 1900);
DISPLAY 0.872340 (3250 1900);
DISPLAY INVISIBLE (3250 1900);
FORCEPROP 1 LAST PATH I148
J 0
(2923 2025);
DISPLAY 0.872340 (2923 2025);
PAINT GREEN (2923 2025);
DISPLAY INVISIBLE (2923 2025);
FORCEADD TAP..1
(2925 2125);
FORCEPROP 3 LASTPIN (2875 2125) SIG_NAME M_E_CPU0_SB_DQS_DN<1>
J 0
(2885 2135);
DISPLAY 0.659574 (2885 2135);
PAINT MONO (2885 2135);
DISPLAY INVISIBLE (2885 2135);
FORCEPROP 1 LASTPIN (2875 2125) BN 1
J 0
(2863 2133);
DISPLAY 0.680851 (2863 2133);
PAINT GREEN (2863 2133);
FORCEPROP 2 LAST CDS_LIB standard
J 0
(2925 2125);
DISPLAY INVISIBLE (2925 2125);
FORCEPROP 1 LAST BODY_TYPE PLUMBING
J 0
(2925 2175);
DISPLAY 0.872340 (2925 2175);
PAINT GREEN (2925 2175);
DISPLAY INVISIBLE (2925 2175);
FORCEPROP 1 LAST HDL_TAP TRUE
J 0
(3250 2000);
DISPLAY 0.872340 (3250 2000);
DISPLAY INVISIBLE (3250 2000);
FORCEPROP 1 LAST PATH I149
J 0
(2923 2125);
DISPLAY 0.872340 (2923 2125);
PAINT GREEN (2923 2125);
DISPLAY INVISIBLE (2923 2125);
FORCEADD OFFPAGE..3
R 2
(-2575 2650);
FORCEPROP 2 LAST $XR1 91 
J 0
(-2914 2650);
DISPLAY 0.638298 (-2914 2650);
PAINT MONO (-2914 2650);
FORCEPROP 2 LAST $XR0 24 
J 0
(-2824 2650);
DISPLAY 0.638298 (-2824 2650);
PAINT MONO (-2824 2650);
FORCEPROP 2 LAST CDS_LIB standard
J 0
(-2575 2650);
PAINT MONO (-2575 2650);
DISPLAY INVISIBLE (-2575 2650);
FORCEPROP 1 LAST OFFPAGE TRUE
J 2
(-2900 2525);
DISPLAY 0.872340 (-2900 2525);
DISPLAY INVISIBLE (-2900 2525);
FORCEPROP 1 LAST COMMENT_BODY TRUE
J 2
(-2525 2550);
DISPLAY 0.872340 (-2525 2550);
PAINT GREEN (-2525 2550);
DISPLAY INVISIBLE (-2525 2550);
FORCEPROP 2 LAST PATH I15
J 0
(-2525 2725);
DISPLAY 1.021277 (-2525 2725);
DISPLAY INVISIBLE (-2525 2725);
FORCEADD TAP..1
(2925 2225);
FORCEPROP 3 LASTPIN (2875 2225) SIG_NAME M_E_CPU0_SB_DQS_DN<2>
J 0
(2885 2235);
DISPLAY 0.659574 (2885 2235);
PAINT MONO (2885 2235);
DISPLAY INVISIBLE (2885 2235);
FORCEPROP 1 LASTPIN (2875 2225) BN 2
J 0
(2863 2233);
DISPLAY 0.680851 (2863 2233);
PAINT GREEN (2863 2233);
FORCEPROP 2 LAST CDS_LIB standard
J 0
(2925 2225);
DISPLAY INVISIBLE (2925 2225);
FORCEPROP 1 LAST BODY_TYPE PLUMBING
J 0
(2925 2275);
DISPLAY 0.872340 (2925 2275);
PAINT GREEN (2925 2275);
DISPLAY INVISIBLE (2925 2275);
FORCEPROP 1 LAST HDL_TAP TRUE
J 0
(3250 2100);
DISPLAY 0.872340 (3250 2100);
DISPLAY INVISIBLE (3250 2100);
FORCEPROP 1 LAST PATH I150
J 0
(2923 2225);
DISPLAY 0.872340 (2923 2225);
PAINT GREEN (2923 2225);
DISPLAY INVISIBLE (2923 2225);
FORCEADD TAP..1
(2925 2325);
FORCEPROP 3 LASTPIN (2875 2325) SIG_NAME M_E_CPU0_SB_DQS_DN<3>
J 0
(2885 2335);
DISPLAY 0.659574 (2885 2335);
PAINT MONO (2885 2335);
DISPLAY INVISIBLE (2885 2335);
FORCEPROP 1 LASTPIN (2875 2325) BN 3
J 0
(2863 2333);
DISPLAY 0.680851 (2863 2333);
PAINT GREEN (2863 2333);
FORCEPROP 2 LAST CDS_LIB standard
J 0
(2925 2325);
PAINT MONO (2925 2325);
DISPLAY INVISIBLE (2925 2325);
FORCEPROP 1 LAST BODY_TYPE PLUMBING
J 0
(2925 2375);
DISPLAY 0.872340 (2925 2375);
PAINT GREEN (2925 2375);
DISPLAY INVISIBLE (2925 2375);
FORCEPROP 1 LAST HDL_TAP TRUE
J 0
(3250 2200);
DISPLAY 0.872340 (3250 2200);
DISPLAY INVISIBLE (3250 2200);
FORCEPROP 1 LAST PATH I151
J 0
(2923 2325);
DISPLAY 0.872340 (2923 2325);
PAINT GREEN (2923 2325);
DISPLAY INVISIBLE (2923 2325);
FORCEADD TAP..1
(2925 2525);
FORCEPROP 3 LASTPIN (2875 2525) SIG_NAME M_E_CPU0_SB_DQS_DN<5>
J 0
(2885 2535);
DISPLAY 0.659574 (2885 2535);
PAINT MONO (2885 2535);
DISPLAY INVISIBLE (2885 2535);
FORCEPROP 1 LASTPIN (2875 2525) BN 5
J 0
(2863 2533);
DISPLAY 0.680851 (2863 2533);
PAINT GREEN (2863 2533);
FORCEPROP 2 LAST CDS_LIB standard
J 0
(2925 2525);
DISPLAY INVISIBLE (2925 2525);
FORCEPROP 1 LAST BODY_TYPE PLUMBING
J 0
(2925 2575);
DISPLAY 0.872340 (2925 2575);
PAINT GREEN (2925 2575);
DISPLAY INVISIBLE (2925 2575);
FORCEPROP 1 LAST HDL_TAP TRUE
J 0
(3250 2400);
DISPLAY 0.872340 (3250 2400);
DISPLAY INVISIBLE (3250 2400);
FORCEPROP 1 LAST PATH I152
J 0
(2923 2525);
DISPLAY 0.872340 (2923 2525);
PAINT GREEN (2923 2525);
DISPLAY INVISIBLE (2923 2525);
FORCEADD TAP..1
(2925 2425);
FORCEPROP 3 LASTPIN (2875 2425) SIG_NAME M_E_CPU0_SB_DQS_DN<4>
J 0
(2885 2435);
DISPLAY 0.659574 (2885 2435);
PAINT MONO (2885 2435);
DISPLAY INVISIBLE (2885 2435);
FORCEPROP 1 LASTPIN (2875 2425) BN 4
J 0
(2863 2433);
DISPLAY 0.680851 (2863 2433);
PAINT GREEN (2863 2433);
FORCEPROP 2 LAST CDS_LIB standard
J 0
(2925 2425);
PAINT MONO (2925 2425);
DISPLAY INVISIBLE (2925 2425);
FORCEPROP 1 LAST BODY_TYPE PLUMBING
J 0
(2925 2475);
DISPLAY 0.872340 (2925 2475);
PAINT GREEN (2925 2475);
DISPLAY INVISIBLE (2925 2475);
FORCEPROP 1 LAST HDL_TAP TRUE
J 0
(3250 2300);
DISPLAY 0.872340 (3250 2300);
DISPLAY INVISIBLE (3250 2300);
FORCEPROP 1 LAST PATH I153
J 0
(2923 2425);
DISPLAY 0.872340 (2923 2425);
PAINT GREEN (2923 2425);
DISPLAY INVISIBLE (2923 2425);
FORCEADD TAP..1
(2925 2625);
FORCEPROP 3 LASTPIN (2875 2625) SIG_NAME M_E_CPU0_SB_DQS_DN<6>
J 0
(2885 2635);
DISPLAY 0.659574 (2885 2635);
PAINT MONO (2885 2635);
DISPLAY INVISIBLE (2885 2635);
FORCEPROP 1 LASTPIN (2875 2625) BN 6
J 0
(2863 2633);
DISPLAY 0.680851 (2863 2633);
PAINT GREEN (2863 2633);
FORCEPROP 2 LAST CDS_LIB standard
J 0
(2925 2625);
DISPLAY INVISIBLE (2925 2625);
FORCEPROP 1 LAST BODY_TYPE PLUMBING
J 0
(2925 2675);
DISPLAY 0.872340 (2925 2675);
PAINT GREEN (2925 2675);
DISPLAY INVISIBLE (2925 2675);
FORCEPROP 1 LAST HDL_TAP TRUE
J 0
(3250 2500);
DISPLAY 0.872340 (3250 2500);
DISPLAY INVISIBLE (3250 2500);
FORCEPROP 1 LAST PATH I154
J 0
(2923 2625);
DISPLAY 0.872340 (2923 2625);
PAINT GREEN (2923 2625);
DISPLAY INVISIBLE (2923 2625);
FORCEADD TAP..1
(2925 2725);
FORCEPROP 3 LASTPIN (2875 2725) SIG_NAME M_E_CPU0_SB_DQS_DN<7>
J 0
(2885 2735);
DISPLAY 0.659574 (2885 2735);
PAINT MONO (2885 2735);
DISPLAY INVISIBLE (2885 2735);
FORCEPROP 1 LASTPIN (2875 2725) BN 7
J 0
(2863 2733);
DISPLAY 0.680851 (2863 2733);
PAINT GREEN (2863 2733);
FORCEPROP 2 LAST CDS_LIB standard
J 0
(2925 2725);
DISPLAY INVISIBLE (2925 2725);
FORCEPROP 1 LAST BODY_TYPE PLUMBING
J 0
(2925 2775);
DISPLAY 0.872340 (2925 2775);
PAINT GREEN (2925 2775);
DISPLAY INVISIBLE (2925 2775);
FORCEPROP 1 LAST HDL_TAP TRUE
J 0
(3250 2600);
DISPLAY 0.872340 (3250 2600);
DISPLAY INVISIBLE (3250 2600);
FORCEPROP 1 LAST PATH I155
J 0
(2923 2725);
DISPLAY 0.872340 (2923 2725);
PAINT GREEN (2923 2725);
DISPLAY INVISIBLE (2923 2725);
FORCEADD TAP..1
(2925 2825);
FORCEPROP 3 LASTPIN (2875 2825) SIG_NAME M_E_CPU0_SB_DQS_DN<8>
J 0
(2885 2835);
DISPLAY 0.659574 (2885 2835);
PAINT MONO (2885 2835);
DISPLAY INVISIBLE (2885 2835);
FORCEPROP 1 LASTPIN (2875 2825) BN 8
J 0
(2863 2833);
DISPLAY 0.680851 (2863 2833);
PAINT GREEN (2863 2833);
FORCEPROP 2 LAST CDS_LIB standard
J 0
(2925 2825);
DISPLAY INVISIBLE (2925 2825);
FORCEPROP 1 LAST BODY_TYPE PLUMBING
J 0
(2925 2875);
DISPLAY 0.872340 (2925 2875);
PAINT GREEN (2925 2875);
DISPLAY INVISIBLE (2925 2875);
FORCEPROP 1 LAST HDL_TAP TRUE
J 0
(3250 2700);
DISPLAY 0.872340 (3250 2700);
DISPLAY INVISIBLE (3250 2700);
FORCEPROP 1 LAST PATH I156
J 0
(2923 2825);
DISPLAY 0.872340 (2923 2825);
PAINT GREEN (2923 2825);
DISPLAY INVISIBLE (2923 2825);
FORCEADD TAP..1
(2925 2925);
FORCEPROP 3 LASTPIN (2875 2925) SIG_NAME M_E_CPU0_SB_DQS_DN<9>
J 0
(2885 2935);
DISPLAY 0.659574 (2885 2935);
PAINT MONO (2885 2935);
DISPLAY INVISIBLE (2885 2935);
FORCEPROP 1 LASTPIN (2875 2925) BN 9
J 0
(2863 2933);
DISPLAY 0.680851 (2863 2933);
PAINT GREEN (2863 2933);
FORCEPROP 2 LAST CDS_LIB standard
J 0
(2925 2925);
DISPLAY INVISIBLE (2925 2925);
FORCEPROP 1 LAST BODY_TYPE PLUMBING
J 0
(2925 2975);
DISPLAY 0.872340 (2925 2975);
PAINT GREEN (2925 2975);
DISPLAY INVISIBLE (2925 2975);
FORCEPROP 1 LAST HDL_TAP TRUE
J 0
(3250 2800);
DISPLAY 0.872340 (3250 2800);
DISPLAY INVISIBLE (3250 2800);
FORCEPROP 1 LAST PATH I157
J 0
(2923 2925);
DISPLAY 0.872340 (2923 2925);
PAINT GREEN (2923 2925);
DISPLAY INVISIBLE (2923 2925);
FORCEADD TAP..1
(2925 3175);
FORCEPROP 3 LASTPIN (2875 3175) SIG_NAME M_E_CPU0_SA_DQS_DN<1>
J 0
(2885 3185);
DISPLAY 0.659574 (2885 3185);
PAINT MONO (2885 3185);
DISPLAY INVISIBLE (2885 3185);
FORCEPROP 1 LASTPIN (2875 3175) BN 1
J 0
(2863 3183);
DISPLAY 0.680851 (2863 3183);
PAINT GREEN (2863 3183);
FORCEPROP 2 LAST CDS_LIB standard
J 0
(2925 3175);
DISPLAY INVISIBLE (2925 3175);
FORCEPROP 1 LAST BODY_TYPE PLUMBING
J 0
(2925 3225);
DISPLAY 0.872340 (2925 3225);
PAINT GREEN (2925 3225);
DISPLAY INVISIBLE (2925 3225);
FORCEPROP 1 LAST HDL_TAP TRUE
J 0
(3250 3050);
DISPLAY 0.872340 (3250 3050);
DISPLAY INVISIBLE (3250 3050);
FORCEPROP 1 LAST PATH I158
J 0
(2923 3175);
DISPLAY 0.872340 (2923 3175);
PAINT GREEN (2923 3175);
DISPLAY INVISIBLE (2923 3175);
FORCEADD TAP..1
(2925 3075);
FORCEPROP 3 LASTPIN (2875 3075) SIG_NAME M_E_CPU0_SA_DQS_DN<0>
J 0
(2885 3085);
DISPLAY 0.659574 (2885 3085);
PAINT MONO (2885 3085);
DISPLAY INVISIBLE (2885 3085);
FORCEPROP 1 LASTPIN (2875 3075) BN 0
J 0
(2863 3083);
DISPLAY 0.680851 (2863 3083);
PAINT GREEN (2863 3083);
FORCEPROP 2 LAST CDS_LIB standard
J 0
(2925 3075);
PAINT MONO (2925 3075);
DISPLAY INVISIBLE (2925 3075);
FORCEPROP 1 LAST BODY_TYPE PLUMBING
J 0
(2925 3125);
DISPLAY 0.872340 (2925 3125);
PAINT GREEN (2925 3125);
DISPLAY INVISIBLE (2925 3125);
FORCEPROP 1 LAST HDL_TAP TRUE
J 0
(3250 2950);
DISPLAY 0.872340 (3250 2950);
DISPLAY INVISIBLE (3250 2950);
FORCEPROP 1 LAST PATH I159
J 0
(2923 3075);
DISPLAY 0.872340 (2923 3075);
PAINT GREEN (2923 3075);
DISPLAY INVISIBLE (2923 3075);
FORCEADD OFFPAGE..1
(-2575 2725);
FORCEPROP 2 LAST $XR0 24 
J 0
(-2796 2725);
DISPLAY 0.638298 (-2796 2725);
PAINT MONO (-2796 2725);
FORCEPROP 2 LAST CDS_LIB standard
J 0
(-2575 2725);
PAINT MONO (-2575 2725);
DISPLAY INVISIBLE (-2575 2725);
FORCEPROP 1 LAST OFFPAGE TRUE
J 0
(-2250 2600);
DISPLAY 0.872340 (-2250 2600);
DISPLAY INVISIBLE (-2250 2600);
FORCEPROP 1 LAST COMMENT_BODY TRUE
J 0
(-2450 2625);
DISPLAY 0.872340 (-2450 2625);
PAINT GREEN (-2450 2625);
DISPLAY INVISIBLE (-2450 2625);
FORCEPROP 2 LAST PATH I16
J 0
(-2525 2800);
DISPLAY 1.021277 (-2525 2800);
DISPLAY INVISIBLE (-2525 2800);
FORCEADD TAP..1
(2925 3275);
FORCEPROP 3 LASTPIN (2875 3275) SIG_NAME M_E_CPU0_SA_DQS_DN<2>
J 0
(2885 3285);
DISPLAY 0.659574 (2885 3285);
PAINT MONO (2885 3285);
DISPLAY INVISIBLE (2885 3285);
FORCEPROP 1 LASTPIN (2875 3275) BN 2
J 0
(2863 3283);
DISPLAY 0.680851 (2863 3283);
PAINT GREEN (2863 3283);
FORCEPROP 2 LAST CDS_LIB standard
J 0
(2925 3275);
DISPLAY INVISIBLE (2925 3275);
FORCEPROP 1 LAST BODY_TYPE PLUMBING
J 0
(2925 3325);
DISPLAY 0.872340 (2925 3325);
PAINT GREEN (2925 3325);
DISPLAY INVISIBLE (2925 3325);
FORCEPROP 1 LAST HDL_TAP TRUE
J 0
(3250 3150);
DISPLAY 0.872340 (3250 3150);
DISPLAY INVISIBLE (3250 3150);
FORCEPROP 1 LAST PATH I160
J 0
(2923 3275);
DISPLAY 0.872340 (2923 3275);
PAINT GREEN (2923 3275);
DISPLAY INVISIBLE (2923 3275);
FORCEADD TAP..1
(2925 3375);
FORCEPROP 3 LASTPIN (2875 3375) SIG_NAME M_E_CPU0_SA_DQS_DN<3>
J 0
(2885 3385);
DISPLAY 0.659574 (2885 3385);
PAINT MONO (2885 3385);
DISPLAY INVISIBLE (2885 3385);
FORCEPROP 1 LASTPIN (2875 3375) BN 3
J 0
(2863 3383);
DISPLAY 0.680851 (2863 3383);
PAINT GREEN (2863 3383);
FORCEPROP 2 LAST CDS_LIB standard
J 0
(2925 3375);
PAINT MONO (2925 3375);
DISPLAY INVISIBLE (2925 3375);
FORCEPROP 1 LAST BODY_TYPE PLUMBING
J 0
(2925 3425);
DISPLAY 0.872340 (2925 3425);
PAINT GREEN (2925 3425);
DISPLAY INVISIBLE (2925 3425);
FORCEPROP 1 LAST HDL_TAP TRUE
J 0
(3250 3250);
DISPLAY 0.872340 (3250 3250);
DISPLAY INVISIBLE (3250 3250);
FORCEPROP 1 LAST PATH I161
J 0
(2923 3375);
DISPLAY 0.872340 (2923 3375);
PAINT GREEN (2923 3375);
DISPLAY INVISIBLE (2923 3375);
FORCEADD TAP..1
(2925 3475);
FORCEPROP 3 LASTPIN (2875 3475) SIG_NAME M_E_CPU0_SA_DQS_DN<4>
J 0
(2885 3485);
DISPLAY 0.659574 (2885 3485);
PAINT MONO (2885 3485);
DISPLAY INVISIBLE (2885 3485);
FORCEPROP 1 LASTPIN (2875 3475) BN 4
J 0
(2863 3483);
DISPLAY 0.680851 (2863 3483);
PAINT GREEN (2863 3483);
FORCEPROP 2 LAST CDS_LIB standard
J 0
(2925 3475);
PAINT MONO (2925 3475);
DISPLAY INVISIBLE (2925 3475);
FORCEPROP 1 LAST BODY_TYPE PLUMBING
J 0
(2925 3525);
DISPLAY 0.872340 (2925 3525);
PAINT GREEN (2925 3525);
DISPLAY INVISIBLE (2925 3525);
FORCEPROP 1 LAST HDL_TAP TRUE
J 0
(3250 3350);
DISPLAY 0.872340 (3250 3350);
DISPLAY INVISIBLE (3250 3350);
FORCEPROP 1 LAST PATH I162
J 0
(2923 3475);
DISPLAY 0.872340 (2923 3475);
PAINT GREEN (2923 3475);
DISPLAY INVISIBLE (2923 3475);
FORCEADD TAP..1
(2925 3675);
FORCEPROP 3 LASTPIN (2875 3675) SIG_NAME M_E_CPU0_SA_DQS_DN<6>
J 0
(2885 3685);
DISPLAY 0.659574 (2885 3685);
PAINT MONO (2885 3685);
DISPLAY INVISIBLE (2885 3685);
FORCEPROP 1 LASTPIN (2875 3675) BN 6
J 0
(2863 3683);
DISPLAY 0.680851 (2863 3683);
PAINT GREEN (2863 3683);
FORCEPROP 2 LAST CDS_LIB standard
J 0
(2925 3675);
DISPLAY INVISIBLE (2925 3675);
FORCEPROP 1 LAST BODY_TYPE PLUMBING
J 0
(2925 3725);
DISPLAY 0.872340 (2925 3725);
PAINT GREEN (2925 3725);
DISPLAY INVISIBLE (2925 3725);
FORCEPROP 1 LAST HDL_TAP TRUE
J 0
(3250 3550);
DISPLAY 0.872340 (3250 3550);
DISPLAY INVISIBLE (3250 3550);
FORCEPROP 1 LAST PATH I163
J 0
(2923 3675);
DISPLAY 0.872340 (2923 3675);
PAINT GREEN (2923 3675);
DISPLAY INVISIBLE (2923 3675);
FORCEADD TAP..1
(2925 3575);
FORCEPROP 3 LASTPIN (2875 3575) SIG_NAME M_E_CPU0_SA_DQS_DN<5>
J 0
(2885 3585);
DISPLAY 0.659574 (2885 3585);
PAINT MONO (2885 3585);
DISPLAY INVISIBLE (2885 3585);
FORCEPROP 1 LASTPIN (2875 3575) BN 5
J 0
(2863 3583);
DISPLAY 0.680851 (2863 3583);
PAINT GREEN (2863 3583);
FORCEPROP 2 LAST CDS_LIB standard
J 0
(2925 3575);
DISPLAY INVISIBLE (2925 3575);
FORCEPROP 1 LAST BODY_TYPE PLUMBING
J 0
(2925 3625);
DISPLAY 0.872340 (2925 3625);
PAINT GREEN (2925 3625);
DISPLAY INVISIBLE (2925 3625);
FORCEPROP 1 LAST HDL_TAP TRUE
J 0
(3250 3450);
DISPLAY 0.872340 (3250 3450);
DISPLAY INVISIBLE (3250 3450);
FORCEPROP 1 LAST PATH I164
J 0
(2923 3575);
DISPLAY 0.872340 (2923 3575);
PAINT GREEN (2923 3575);
DISPLAY INVISIBLE (2923 3575);
FORCEADD TAP..1
(2925 3775);
FORCEPROP 3 LASTPIN (2875 3775) SIG_NAME M_E_CPU0_SA_DQS_DN<7>
J 0
(2885 3785);
DISPLAY 0.659574 (2885 3785);
PAINT MONO (2885 3785);
DISPLAY INVISIBLE (2885 3785);
FORCEPROP 1 LASTPIN (2875 3775) BN 7
J 0
(2863 3783);
DISPLAY 0.680851 (2863 3783);
PAINT GREEN (2863 3783);
FORCEPROP 2 LAST CDS_LIB standard
J 0
(2925 3775);
DISPLAY INVISIBLE (2925 3775);
FORCEPROP 1 LAST BODY_TYPE PLUMBING
J 0
(2925 3825);
DISPLAY 0.872340 (2925 3825);
PAINT GREEN (2925 3825);
DISPLAY INVISIBLE (2925 3825);
FORCEPROP 1 LAST HDL_TAP TRUE
J 0
(3250 3650);
DISPLAY 0.872340 (3250 3650);
DISPLAY INVISIBLE (3250 3650);
FORCEPROP 1 LAST PATH I165
J 0
(2923 3775);
DISPLAY 0.872340 (2923 3775);
PAINT GREEN (2923 3775);
DISPLAY INVISIBLE (2923 3775);
FORCEADD OFFPAGE..2
(3875 2950);
FORCEPROP 2 LAST $XR1 91 
J 0
(4154 2950);
DISPLAY 0.638298 (4154 2950);
PAINT MONO (4154 2950);
FORCEPROP 2 LAST $XR0 24 
J 0
(4064 2950);
DISPLAY 0.638298 (4064 2950);
PAINT MONO (4064 2950);
FORCEPROP 2 LAST CDS_LIB standard
J 0
(3875 2950);
PAINT MONO (3875 2950);
DISPLAY INVISIBLE (3875 2950);
FORCEPROP 1 LAST OFFPAGE TRUE
J 0
(4200 2825);
DISPLAY 1.170213 (4200 2825);
PAINT GREEN (4200 2825);
DISPLAY INVISIBLE (4200 2825);
FORCEPROP 1 LAST COMMENT_BODY TRUE
J 0
(3830 2855);
DISPLAY 1.170213 (3830 2855);
PAINT GREEN (3830 2855);
DISPLAY INVISIBLE (3830 2855);
FORCEPROP 2 LAST PATH I166
J 0
(4050 3025);
DISPLAY 1.021277 (4050 3025);
DISPLAY INVISIBLE (4050 3025);
FORCEADD OFFPAGE..2
(3875 3000);
FORCEPROP 2 LAST $XR1 91 
J 0
(4154 3000);
DISPLAY 0.638298 (4154 3000);
PAINT MONO (4154 3000);
FORCEPROP 2 LAST $XR0 24 
J 0
(4064 3000);
DISPLAY 0.638298 (4064 3000);
PAINT MONO (4064 3000);
FORCEPROP 2 LAST CDS_LIB standard
J 0
(3875 3000);
PAINT MONO (3875 3000);
DISPLAY INVISIBLE (3875 3000);
FORCEPROP 1 LAST OFFPAGE TRUE
J 0
(4200 2875);
DISPLAY 1.170213 (4200 2875);
PAINT GREEN (4200 2875);
DISPLAY INVISIBLE (4200 2875);
FORCEPROP 1 LAST COMMENT_BODY TRUE
J 0
(3830 2905);
DISPLAY 1.170213 (3830 2905);
PAINT GREEN (3830 2905);
DISPLAY INVISIBLE (3830 2905);
FORCEPROP 2 LAST PATH I167
J 0
(4050 3075);
DISPLAY 1.021277 (4050 3075);
DISPLAY INVISIBLE (4050 3075);
FORCEADD OFFPAGE..3
(825 4050);
FORCEPROP 2 LAST $XR1 91 
J 0
(1129 4050);
DISPLAY 0.638298 (1129 4050);
PAINT MONO (1129 4050);
FORCEPROP 2 LAST $XR0 24 
J 0
(1039 4050);
DISPLAY 0.638298 (1039 4050);
PAINT MONO (1039 4050);
FORCEPROP 2 LAST CDS_LIB standard
J 2
(825 4050);
DISPLAY INVISIBLE (825 4050);
FORCEPROP 1 LAST OFFPAGE TRUE
J 0
(1150 3925);
DISPLAY 0.872340 (1150 3925);
DISPLAY INVISIBLE (1150 3925);
FORCEPROP 1 LAST COMMENT_BODY TRUE
J 0
(775 3950);
DISPLAY 0.872340 (775 3950);
PAINT GREEN (775 3950);
DISPLAY INVISIBLE (775 3950);
FORCEPROP 2 LAST PATH I168
J 0
(1025 4125);
DISPLAY 1.021277 (1025 4125);
DISPLAY INVISIBLE (1025 4125);
FORCEADD TAP..1
(2750 3825);
FORCEPROP 3 LASTPIN (2700 3825) SIG_NAME M_E_CPU0_SA_DQS_DP<7>
J 0
(2710 3835);
DISPLAY 0.659574 (2710 3835);
PAINT MONO (2710 3835);
DISPLAY INVISIBLE (2710 3835);
FORCEPROP 1 LASTPIN (2700 3825) BN 7
J 0
(2688 3833);
DISPLAY 0.680851 (2688 3833);
PAINT GREEN (2688 3833);
FORCEPROP 2 LAST CDS_LIB standard
J 0
(2750 3825);
DISPLAY INVISIBLE (2750 3825);
FORCEPROP 1 LAST BODY_TYPE PLUMBING
J 0
(2750 3875);
DISPLAY 0.872340 (2750 3875);
PAINT GREEN (2750 3875);
DISPLAY INVISIBLE (2750 3875);
FORCEPROP 1 LAST HDL_TAP TRUE
J 0
(3075 3700);
DISPLAY 0.872340 (3075 3700);
DISPLAY INVISIBLE (3075 3700);
FORCEPROP 1 LAST PATH I169
J 0
(2748 3825);
DISPLAY 0.872340 (2748 3825);
PAINT GREEN (2748 3825);
DISPLAY INVISIBLE (2748 3825);
FORCEADD OFFPAGE..1
(-2575 2775);
FORCEPROP 2 LAST $XR0 24 
J 0
(-2796 2775);
DISPLAY 0.638298 (-2796 2775);
PAINT MONO (-2796 2775);
FORCEPROP 2 LAST CDS_LIB standard
J 0
(-2575 2775);
PAINT MONO (-2575 2775);
DISPLAY INVISIBLE (-2575 2775);
FORCEPROP 1 LAST OFFPAGE TRUE
J 0
(-2250 2650);
DISPLAY 0.872340 (-2250 2650);
DISPLAY INVISIBLE (-2250 2650);
FORCEPROP 1 LAST COMMENT_BODY TRUE
J 0
(-2450 2675);
DISPLAY 0.872340 (-2450 2675);
PAINT GREEN (-2450 2675);
DISPLAY INVISIBLE (-2450 2675);
FORCEPROP 2 LAST PATH I17
J 0
(-2525 2850);
DISPLAY 1.021277 (-2525 2850);
DISPLAY INVISIBLE (-2525 2850);
FORCEADD TAP..1
(2750 3925);
FORCEPROP 3 LASTPIN (2700 3925) SIG_NAME M_E_CPU0_SA_DQS_DP<8>
J 0
(2710 3935);
DISPLAY 0.659574 (2710 3935);
PAINT MONO (2710 3935);
DISPLAY INVISIBLE (2710 3935);
FORCEPROP 1 LASTPIN (2700 3925) BN 8
J 0
(2688 3933);
DISPLAY 0.680851 (2688 3933);
PAINT GREEN (2688 3933);
FORCEPROP 2 LAST CDS_LIB standard
J 0
(2750 3925);
DISPLAY INVISIBLE (2750 3925);
FORCEPROP 1 LAST BODY_TYPE PLUMBING
J 0
(2750 3975);
DISPLAY 0.872340 (2750 3975);
PAINT GREEN (2750 3975);
DISPLAY INVISIBLE (2750 3975);
FORCEPROP 1 LAST HDL_TAP TRUE
J 0
(3075 3800);
DISPLAY 0.872340 (3075 3800);
DISPLAY INVISIBLE (3075 3800);
FORCEPROP 1 LAST PATH I170
J 0
(2748 3925);
DISPLAY 0.872340 (2748 3925);
PAINT GREEN (2748 3925);
DISPLAY INVISIBLE (2748 3925);
FORCEADD TAP..1
(2750 4025);
FORCEPROP 3 LASTPIN (2700 4025) SIG_NAME M_E_CPU0_SA_DQS_DP<9>
J 0
(2710 4035);
DISPLAY 0.659574 (2710 4035);
PAINT MONO (2710 4035);
DISPLAY INVISIBLE (2710 4035);
FORCEPROP 1 LASTPIN (2700 4025) BN 9
J 0
(2688 4033);
DISPLAY 0.680851 (2688 4033);
PAINT GREEN (2688 4033);
FORCEPROP 2 LAST CDS_LIB standard
J 0
(2750 4025);
DISPLAY INVISIBLE (2750 4025);
FORCEPROP 1 LAST BODY_TYPE PLUMBING
J 0
(2750 4075);
DISPLAY 0.872340 (2750 4075);
PAINT GREEN (2750 4075);
DISPLAY INVISIBLE (2750 4075);
FORCEPROP 1 LAST HDL_TAP TRUE
J 0
(3075 3900);
DISPLAY 0.872340 (3075 3900);
DISPLAY INVISIBLE (3075 3900);
FORCEPROP 1 LAST PATH I171
J 0
(2748 4025);
DISPLAY 0.872340 (2748 4025);
PAINT GREEN (2748 4025);
DISPLAY INVISIBLE (2748 4025);
FORCEADD TAP..1
(2925 3875);
FORCEPROP 3 LASTPIN (2875 3875) SIG_NAME M_E_CPU0_SA_DQS_DN<8>
J 0
(2885 3885);
DISPLAY 0.659574 (2885 3885);
PAINT MONO (2885 3885);
DISPLAY INVISIBLE (2885 3885);
FORCEPROP 1 LASTPIN (2875 3875) BN 8
J 0
(2863 3883);
DISPLAY 0.680851 (2863 3883);
PAINT GREEN (2863 3883);
FORCEPROP 2 LAST CDS_LIB standard
J 0
(2925 3875);
DISPLAY INVISIBLE (2925 3875);
FORCEPROP 1 LAST BODY_TYPE PLUMBING
J 0
(2925 3925);
DISPLAY 0.872340 (2925 3925);
PAINT GREEN (2925 3925);
DISPLAY INVISIBLE (2925 3925);
FORCEPROP 1 LAST HDL_TAP TRUE
J 0
(3250 3750);
DISPLAY 0.872340 (3250 3750);
DISPLAY INVISIBLE (3250 3750);
FORCEPROP 1 LAST PATH I172
J 0
(2923 3875);
DISPLAY 0.872340 (2923 3875);
PAINT GREEN (2923 3875);
DISPLAY INVISIBLE (2923 3875);
FORCEADD TAP..1
(2925 3975);
FORCEPROP 3 LASTPIN (2875 3975) SIG_NAME M_E_CPU0_SA_DQS_DN<9>
J 0
(2885 3985);
DISPLAY 0.659574 (2885 3985);
PAINT MONO (2885 3985);
DISPLAY INVISIBLE (2885 3985);
FORCEPROP 1 LASTPIN (2875 3975) BN 9
J 0
(2863 3983);
DISPLAY 0.680851 (2863 3983);
PAINT GREEN (2863 3983);
FORCEPROP 2 LAST CDS_LIB standard
J 0
(2925 3975);
DISPLAY INVISIBLE (2925 3975);
FORCEPROP 1 LAST BODY_TYPE PLUMBING
J 0
(2925 4025);
DISPLAY 0.872340 (2925 4025);
PAINT GREEN (2925 4025);
DISPLAY INVISIBLE (2925 4025);
FORCEPROP 1 LAST HDL_TAP TRUE
J 0
(3250 3850);
DISPLAY 0.872340 (3250 3850);
DISPLAY INVISIBLE (3250 3850);
FORCEPROP 1 LAST PATH I173
J 0
(2923 3975);
DISPLAY 0.872340 (2923 3975);
PAINT GREEN (2923 3975);
DISPLAY INVISIBLE (2923 3975);
FORCEADD OFFPAGE..2
(3875 4000);
FORCEPROP 2 LAST $XR1 91 
J 0
(4154 4000);
DISPLAY 0.638298 (4154 4000);
PAINT MONO (4154 4000);
FORCEPROP 2 LAST $XR0 24 
J 0
(4064 4000);
DISPLAY 0.638298 (4064 4000);
PAINT MONO (4064 4000);
FORCEPROP 2 LAST CDS_LIB standard
J 0
(3875 4000);
PAINT MONO (3875 4000);
DISPLAY INVISIBLE (3875 4000);
FORCEPROP 1 LAST OFFPAGE TRUE
J 0
(4200 3875);
DISPLAY 1.170213 (4200 3875);
PAINT GREEN (4200 3875);
DISPLAY INVISIBLE (4200 3875);
FORCEPROP 1 LAST COMMENT_BODY TRUE
J 0
(3830 3905);
DISPLAY 1.170213 (3830 3905);
PAINT GREEN (3830 3905);
DISPLAY INVISIBLE (3830 3905);
FORCEPROP 2 LAST PATH I174
J 0
(4050 4075);
DISPLAY 1.021277 (4050 4075);
DISPLAY INVISIBLE (4050 4075);
FORCEADD OFFPAGE..2
(3875 4050);
FORCEPROP 2 LAST $XR1 91 
J 0
(4154 4050);
DISPLAY 0.638298 (4154 4050);
PAINT MONO (4154 4050);
FORCEPROP 2 LAST $XR0 24 
J 0
(4064 4050);
DISPLAY 0.638298 (4064 4050);
PAINT MONO (4064 4050);
FORCEPROP 2 LAST CDS_LIB standard
J 0
(3875 4050);
PAINT MONO (3875 4050);
DISPLAY INVISIBLE (3875 4050);
FORCEPROP 1 LAST OFFPAGE TRUE
J 0
(4200 3925);
DISPLAY 1.170213 (4200 3925);
PAINT GREEN (4200 3925);
DISPLAY INVISIBLE (4200 3925);
FORCEPROP 1 LAST COMMENT_BODY TRUE
J 0
(3830 3955);
DISPLAY 1.170213 (3830 3955);
PAINT GREEN (3830 3955);
DISPLAY INVISIBLE (3830 3955);
FORCEPROP 2 LAST PATH I175
J 0
(4050 4125);
DISPLAY 1.021277 (4050 4125);
DISPLAY INVISIBLE (4050 4125);
FORCEADD VCC_CORE..1
(4425 4575);
FORCEPROP 3 LASTPIN (4425 4525) SIG_NAME P12V_S3_AUX_CPU0_NVDIMM\g
J 0
(4435 4535);
DISPLAY 0.659574 (4435 4535);
PAINT MONO (4435 4535);
DISPLAY INVISIBLE (4435 4535);
FORCEPROP 1 LAST HDL_POWER P12V_S3_AUX_CPU0_NVDIMM
J 1
(4425 4625);
DISPLAY 1.148936 (4425 4625);
PAINT GREEN (4425 4625);
FORCEPROP 2 LAST CDS_LIB logical_power
J 0
(4425 4575);
PAINT MONO (4425 4575);
DISPLAY INVISIBLE (4425 4575);
FORCEPROP 1 LAST PATH I176
J 0
(4475 4600);
DISPLAY 0.872340 (4475 4600);
PAINT AQUA (4475 4600);
DISPLAY INVISIBLE (4475 4600);
FORCEADD UNIVERSAL_GND..1
(6125 325);
FORCEPROP 3 LASTPIN (6125 375) SIG_NAME GND\g
J 0
(6135 385);
DISPLAY 0.659574 (6135 385);
PAINT MONO (6135 385);
DISPLAY INVISIBLE (6135 385);
FORCEPROP 2 LAST CDS_LIB logical_power
J 0
(6125 325);
PAINT MONO (6125 325);
DISPLAY INVISIBLE (6125 325);
FORCEPROP 1 LAST HDL_POWER GND
J 1
(6150 250);
DISPLAY 0.872340 (6150 250);
PAINT GREEN (6150 250);
DISPLAY INVISIBLE (6150 250);
FORCEPROP 1 LAST PATH I177
J 0
(6200 325);
DISPLAY 0.872340 (6200 325);
PAINT AQUA (6200 325);
DISPLAY INVISIBLE (6200 325);
FORCEADD SCONN288_ADR50017P130CC..2
(1850 3025);
FORCEPROP 1 LAST PART_NUMBER DFHST8FS461
J 0
(1257 4325);
DISPLAY 0.723404 (1257 4325);
PAINT GREEN (1257 4325);
DISPLAY INVISIBLE (1257 4325);
FORCEPROP 1 LAST MATERIAL IO
J 0
(1257 4198);
DISPLAY 0.723404 (1257 4198);
PAINT GREEN (1257 4198);
FORCEPROP 2 LAST PART_TYPE SMLF
J 0
(1268 4478);
DISPLAY 1.021277 (1268 4478);
FORCEPROP 2 LAST VALUE SCONN288_ADR50017-P130CC
J 0
(1268 4428);
DISPLAY 1.021277 (1268 4428);
FORCEPROP 1 LAST LOCATION J9
J 0
(1250 4375);
DISPLAY 0.723404 (1250 4375);
PAINT GREEN (1250 4375);
FORCEPROP 0 LASTPIN (2600 3075) $PN 12
J 0
(2610 3085);
DISPLAY 0.680851 (2610 3085);
PAINT MONO (2610 3085);
FORCEPROP 0 LASTPIN (2600 3125) $PN 11
J 0
(2610 3135);
DISPLAY 0.680851 (2610 3135);
PAINT MONO (2610 3135);
FORCEPROP 0 LASTPIN (2600 2025) $PN 105
J 0
(2610 2035);
DISPLAY 0.680851 (2610 2035);
PAINT MONO (2610 2035);
FORCEPROP 0 LASTPIN (2600 2075) $PN 104
J 0
(2610 2085);
DISPLAY 0.680851 (2610 2085);
PAINT MONO (2610 2085);
FORCEPROP 0 LASTPIN (2600 3175) $PN 23
J 0
(2610 3185);
DISPLAY 0.680851 (2610 3185);
PAINT MONO (2610 3185);
FORCEPROP 0 LASTPIN (2600 3225) $PN 22
J 0
(2610 3235);
DISPLAY 0.680851 (2610 3235);
PAINT MONO (2610 3235);
FORCEPROP 0 LASTPIN (2600 2125) $PN 116
J 0
(2610 2135);
DISPLAY 0.680851 (2610 2135);
PAINT MONO (2610 2135);
FORCEPROP 0 LASTPIN (2600 2175) $PN 115
J 0
(2610 2185);
DISPLAY 0.680851 (2610 2185);
PAINT MONO (2610 2185);
FORCEPROP 0 LASTPIN (2600 3275) $PN 34
J 0
(2610 3285);
DISPLAY 0.680851 (2610 3285);
PAINT MONO (2610 3285);
FORCEPROP 0 LASTPIN (2600 3325) $PN 33
J 0
(2610 3335);
DISPLAY 0.680851 (2610 3335);
PAINT MONO (2610 3335);
FORCEPROP 0 LASTPIN (2600 2225) $PN 127
J 0
(2610 2235);
DISPLAY 0.680851 (2610 2235);
PAINT MONO (2610 2235);
FORCEPROP 0 LASTPIN (2600 2275) $PN 126
J 0
(2610 2285);
DISPLAY 0.680851 (2610 2285);
PAINT MONO (2610 2285);
FORCEPROP 0 LASTPIN (2600 3375) $PN 45
J 0
(2610 3385);
DISPLAY 0.680851 (2610 3385);
PAINT MONO (2610 3385);
FORCEPROP 0 LASTPIN (2600 3425) $PN 44
J 0
(2610 3435);
DISPLAY 0.680851 (2610 3435);
PAINT MONO (2610 3435);
FORCEPROP 0 LASTPIN (2600 2325) $PN 138
J 0
(2610 2335);
DISPLAY 0.680851 (2610 2335);
PAINT MONO (2610 2335);
FORCEPROP 0 LASTPIN (2600 2375) $PN 137
J 0
(2610 2385);
DISPLAY 0.680851 (2610 2385);
PAINT MONO (2610 2385);
FORCEPROP 0 LASTPIN (2600 3475) $PN 56
J 0
(2610 3485);
DISPLAY 0.680851 (2610 3485);
PAINT MONO (2610 3485);
FORCEPROP 0 LASTPIN (2600 3525) $PN 55
J 0
(2610 3535);
DISPLAY 0.680851 (2610 3535);
PAINT MONO (2610 3535);
FORCEPROP 0 LASTPIN (2600 2425) $PN 238
J 0
(2610 2435);
DISPLAY 0.680851 (2610 2435);
PAINT MONO (2610 2435);
FORCEPROP 0 LASTPIN (2600 2475) $PN 239
J 0
(2610 2485);
DISPLAY 0.680851 (2610 2485);
PAINT MONO (2610 2485);
FORCEPROP 0 LASTPIN (2600 3575) $PN 156
J 0
(2610 3585);
DISPLAY 0.680851 (2610 3585);
PAINT MONO (2610 3585);
FORCEPROP 0 LASTPIN (2600 3625) $PN 157
J 0
(2610 3635);
DISPLAY 0.680851 (2610 3635);
PAINT MONO (2610 3635);
FORCEPROP 0 LASTPIN (2600 2525) $PN 249
J 0
(2610 2535);
DISPLAY 0.680851 (2610 2535);
PAINT MONO (2610 2535);
FORCEPROP 0 LASTPIN (2600 2575) $PN 250
J 0
(2610 2585);
DISPLAY 0.680851 (2610 2585);
PAINT MONO (2610 2585);
FORCEPROP 0 LASTPIN (2600 3675) $PN 167
J 0
(2610 3685);
DISPLAY 0.680851 (2610 3685);
PAINT MONO (2610 3685);
FORCEPROP 0 LASTPIN (2600 3725) $PN 168
J 0
(2610 3735);
DISPLAY 0.680851 (2610 3735);
PAINT MONO (2610 3735);
FORCEPROP 0 LASTPIN (2600 2625) $PN 260
J 0
(2610 2635);
DISPLAY 0.680851 (2610 2635);
PAINT MONO (2610 2635);
FORCEPROP 0 LASTPIN (2600 2675) $PN 261
J 0
(2610 2685);
DISPLAY 0.680851 (2610 2685);
PAINT MONO (2610 2685);
FORCEPROP 0 LASTPIN (2600 3775) $PN 178
J 0
(2610 3785);
DISPLAY 0.680851 (2610 3785);
PAINT MONO (2610 3785);
FORCEPROP 0 LASTPIN (2600 3825) $PN 179
J 0
(2610 3835);
DISPLAY 0.680851 (2610 3835);
PAINT MONO (2610 3835);
FORCEPROP 0 LASTPIN (2600 2725) $PN 271
J 0
(2610 2735);
DISPLAY 0.680851 (2610 2735);
PAINT MONO (2610 2735);
FORCEPROP 0 LASTPIN (2600 2775) $PN 272
J 0
(2610 2785);
DISPLAY 0.680851 (2610 2785);
PAINT MONO (2610 2785);
FORCEPROP 0 LASTPIN (2600 3875) $PN 189
J 0
(2610 3885);
DISPLAY 0.680851 (2610 3885);
PAINT MONO (2610 3885);
FORCEPROP 0 LASTPIN (2600 3925) $PN 190
J 0
(2610 3935);
DISPLAY 0.680851 (2610 3935);
PAINT MONO (2610 3935);
FORCEPROP 0 LASTPIN (2600 2825) $PN 282
J 0
(2610 2835);
DISPLAY 0.680851 (2610 2835);
PAINT MONO (2610 2835);
FORCEPROP 0 LASTPIN (2600 2875) $PN 283
J 0
(2610 2885);
DISPLAY 0.680851 (2610 2885);
PAINT MONO (2610 2885);
FORCEPROP 0 LASTPIN (2600 3975) $PN 200
J 0
(2610 3985);
DISPLAY 0.680851 (2610 3985);
PAINT MONO (2610 3985);
FORCEPROP 0 LASTPIN (2600 4025) $PN 201
J 0
(2610 4035);
DISPLAY 0.680851 (2610 4035);
PAINT MONO (2610 4035);
FORCEPROP 0 LASTPIN (2600 2925) $PN 94
J 0
(2610 2935);
DISPLAY 0.680851 (2610 2935);
PAINT MONO (2610 2935);
FORCEPROP 0 LASTPIN (2600 2975) $PN 93
J 0
(2610 2985);
DISPLAY 0.680851 (2610 2985);
PAINT MONO (2610 2985);
FORCEPROP 1 LAST NEEDS_NO_SIZE TRUE
J 0
(1850 3025);
DISPLAY 0.723404 (1850 3025);
PAINT GREEN (1850 3025);
DISPLAY INVISIBLE (1850 3025);
FORCEPROP 1 LAST CDS_LMAN_SYM_OUTLINE -600,1150,600,-1150
J 0
(1850 3025);
DISPLAY 0.468085 (1850 3025);
PAINT GREEN (1850 3025);
DISPLAY INVISIBLE (1850 3025);
FORCEPROP 2 LAST CDS_LIB pure_quanta
J 0
(1850 3025);
DISPLAY INVISIBLE (1850 3025);
FORCEPROP 0 LAST $SEC 2
J 0
(1275 4550);
DISPLAY 0.680851 (1275 4550);
PAINT MONO (1275 4550);
DISPLAY INVISIBLE (1275 4550);
FORCEPROP 0 LAST CDS_SEC 2
J 0
(1275 4550);
DISPLAY 1.021277 (1275 4550);
DISPLAY INVISIBLE (1275 4550);
FORCEPROP 1 LAST PATH I178
J 0
(1850 3025);
DISPLAY 0.723404 (1850 3025);
PAINT GREEN (1850 3025);
DISPLAY INVISIBLE (1850 3025);
FORCEADD Q_RES..1
(-2650 1325);
FORCEPROP 1 LAST PART_NUMBER CS04992FB07
J 0
(-2550 1300);
DISPLAY 0.404255 (-2550 1300);
DISPLAY INVISIBLE (-2550 1300);
FORCEPROP 1 LAST MATERIAL CHIP
J 0
(-2550 1275);
DISPLAY 0.404255 (-2550 1275);
FORCEPROP 1 LAST VALUE 49.9
J 2
(-2425 1325);
DISPLAY 0.510638 (-2425 1325);
FORCEPROP 1 LAST $LOCATION R3883
J 0
(-2900 1325);
DISPLAY 0.638298 (-2900 1325);
FORCEPROP 1 LASTPIN (-2750 1325) $PN 1
J 0
(-2738 1337);
DISPLAY 0.787234 (-2738 1337);
PAINT MONO (-2738 1337);
FORCEPROP 1 LASTPIN (-2550 1325) $PN 2
J 0
(-2588 1337);
DISPLAY 0.787234 (-2588 1337);
PAINT MONO (-2588 1337);
FORCEPROP 2 LAST CDS_LIB pure_quanta
J 0
(-2650 1325);
DISPLAY INVISIBLE (-2650 1325);
FORCEPROP 1 LAST PACK_TYPE 0402LF
J 0
(-2350 1325);
DISPLAY 0.510638 (-2350 1325);
DISPLAY INVISIBLE (-2350 1325);
FORCEPROP 1 LAST TOLERANCE 1%
J 0
(-2425 1325);
DISPLAY 0.510638 (-2425 1325);
DISPLAY INVISIBLE (-2425 1325);
FORCEPROP 1 LAST WATTAGE 1/16W
J 2
(-2350 1275);
DISPLAY 0.404255 (-2350 1275);
DISPLAY INVISIBLE (-2350 1275);
FORCEPROP 0 LAST CDS_LOCATION R3883
J 0
(-2800 1375);
DISPLAY 1.021277 (-2800 1375);
DISPLAY INVISIBLE (-2800 1375);
FORCEPROP 0 LAST $SEC 1
J 0
(-2800 1375);
DISPLAY 0.680851 (-2800 1375);
PAINT MONO (-2800 1375);
DISPLAY INVISIBLE (-2800 1375);
FORCEPROP 0 LAST CDS_SEC 1
J 0
(-2800 1375);
DISPLAY 1.021277 (-2800 1375);
DISPLAY INVISIBLE (-2800 1375);
FORCEPROP 1 LAST PATH I179
J 0
(-2700 1475);
DISPLAY 0.978723 (-2700 1475);
PAINT WHITE (-2700 1475);
DISPLAY INVISIBLE (-2700 1475);
FORCEADD OFFPAGE..1
(-2575 3025);
FORCEPROP 2 LAST $XR0 24 
J 0
(-2796 3025);
DISPLAY 0.638298 (-2796 3025);
PAINT MONO (-2796 3025);
FORCEPROP 2 LAST CDS_LIB standard
J 0
(-2575 3025);
PAINT MONO (-2575 3025);
DISPLAY INVISIBLE (-2575 3025);
FORCEPROP 1 LAST OFFPAGE TRUE
J 0
(-2250 2900);
DISPLAY 0.872340 (-2250 2900);
DISPLAY INVISIBLE (-2250 2900);
FORCEPROP 1 LAST COMMENT_BODY TRUE
J 0
(-2450 2925);
DISPLAY 0.872340 (-2450 2925);
PAINT GREEN (-2450 2925);
DISPLAY INVISIBLE (-2450 2925);
FORCEPROP 2 LAST PATH I18
J 0
(-2525 3100);
DISPLAY 1.021277 (-2525 3100);
DISPLAY INVISIBLE (-2525 3100);
FORCEADD OFFPAGE..1
(-1425 1250);
FORCEPROP 2 LAST $XR7 97 
J 0
(-2307 1250);
DISPLAY 0.638298 (-2307 1250);
PAINT MONO (-2307 1250);
FORCEPROP 2 LAST $XR6 96 
J 0
(-2217 1250);
DISPLAY 0.638298 (-2217 1250);
PAINT MONO (-2217 1250);
FORCEPROP 2 LAST $XR5 95 
J 0
(-2127 1250);
DISPLAY 0.638298 (-2127 1250);
PAINT MONO (-2127 1250);
FORCEPROP 2 LAST $XR4 94 
J 0
(-2037 1250);
DISPLAY 0.638298 (-2037 1250);
PAINT MONO (-2037 1250);
FORCEPROP 2 LAST $XR3 93 
J 0
(-1947 1250);
DISPLAY 0.638298 (-1947 1250);
PAINT MONO (-1947 1250);
FORCEPROP 2 LAST $XR2 92 
J 0
(-1857 1250);
DISPLAY 0.638298 (-1857 1250);
PAINT MONO (-1857 1250);
FORCEPROP 2 LAST $XR1 91 
J 0
(-1767 1250);
DISPLAY 0.638298 (-1767 1250);
PAINT MONO (-1767 1250);
FORCEPROP 2 LAST $XR0 229 
J 0
(-1677 1250);
DISPLAY 0.638298 (-1677 1250);
PAINT MONO (-1677 1250);
FORCEPROP 2 LAST CDS_LIB standard
J 2
(-1425 1250);
DISPLAY INVISIBLE (-1425 1250);
FORCEPROP 1 LAST OFFPAGE TRUE
J 0
(-1100 1125);
DISPLAY 0.872340 (-1100 1125);
DISPLAY INVISIBLE (-1100 1125);
FORCEPROP 1 LAST COMMENT_BODY TRUE
J 0
(-1300 1150);
DISPLAY 0.872340 (-1300 1150);
PAINT GREEN (-1300 1150);
DISPLAY INVISIBLE (-1300 1150);
FORCEPROP 2 LAST PATH I180
J 2
(-1600 1325);
DISPLAY 1.021277 (-1600 1325);
DISPLAY INVISIBLE (-1600 1325);
FORCEADD OFFPAGE..1
(-2575 2875);
FORCEPROP 2 LAST $XR0 24 
J 0
(-2796 2875);
DISPLAY 0.638298 (-2796 2875);
PAINT MONO (-2796 2875);
FORCEPROP 2 LAST CDS_LIB standard
J 0
(-2575 2875);
PAINT MONO (-2575 2875);
DISPLAY INVISIBLE (-2575 2875);
FORCEPROP 1 LAST OFFPAGE TRUE
J 0
(-2250 2750);
DISPLAY 0.872340 (-2250 2750);
DISPLAY INVISIBLE (-2250 2750);
FORCEPROP 1 LAST COMMENT_BODY TRUE
J 0
(-2450 2775);
DISPLAY 0.872340 (-2450 2775);
PAINT GREEN (-2450 2775);
DISPLAY INVISIBLE (-2450 2775);
FORCEPROP 2 LAST PATH I19
J 0
(-2525 2950);
DISPLAY 1.021277 (-2525 2950);
DISPLAY INVISIBLE (-2525 2950);
FORCEADD OFFPAGE..2
R 2
(-2575 75);
FORCEPROP 2 LAST $XR0 90 
J 0
(-2799 75);
DISPLAY 0.638298 (-2799 75);
PAINT MONO (-2799 75);
FORCEPROP 2 LAST CDS_LIB standard
J 0
(-2575 75);
PAINT MONO (-2575 75);
DISPLAY INVISIBLE (-2575 75);
FORCEPROP 1 LAST OFFPAGE TRUE
J 2
(-2900 -50);
DISPLAY 0.872340 (-2900 -50);
DISPLAY INVISIBLE (-2900 -50);
FORCEPROP 1 LAST COMMENT_BODY TRUE
J 2
(-2530 -20);
DISPLAY 0.872340 (-2530 -20);
PAINT GREEN (-2530 -20);
DISPLAY INVISIBLE (-2530 -20);
FORCEPROP 2 LAST PATH I2
J 0
(-2525 150);
DISPLAY 1.021277 (-2525 150);
DISPLAY INVISIBLE (-2525 150);
FORCEADD OFFPAGE..1
(-2575 2925);
FORCEPROP 2 LAST $XR0 24 
J 0
(-2796 2925);
DISPLAY 0.638298 (-2796 2925);
PAINT MONO (-2796 2925);
FORCEPROP 2 LAST CDS_LIB standard
J 0
(-2575 2925);
PAINT MONO (-2575 2925);
DISPLAY INVISIBLE (-2575 2925);
FORCEPROP 1 LAST OFFPAGE TRUE
J 0
(-2250 2800);
DISPLAY 0.872340 (-2250 2800);
DISPLAY INVISIBLE (-2250 2800);
FORCEPROP 1 LAST COMMENT_BODY TRUE
J 0
(-2450 2825);
DISPLAY 0.872340 (-2450 2825);
PAINT GREEN (-2450 2825);
DISPLAY INVISIBLE (-2450 2825);
FORCEPROP 2 LAST PATH I20
J 0
(-2525 3000);
DISPLAY 1.021277 (-2525 3000);
DISPLAY INVISIBLE (-2525 3000);
FORCEADD OFFPAGE..1
(-2575 3075);
FORCEPROP 2 LAST $XR0 24 
J 0
(-2796 3075);
DISPLAY 0.638298 (-2796 3075);
PAINT MONO (-2796 3075);
FORCEPROP 2 LAST CDS_LIB standard
J 0
(-2575 3075);
PAINT MONO (-2575 3075);
DISPLAY INVISIBLE (-2575 3075);
FORCEPROP 1 LAST OFFPAGE TRUE
J 0
(-2250 2950);
DISPLAY 0.872340 (-2250 2950);
DISPLAY INVISIBLE (-2250 2950);
FORCEPROP 1 LAST COMMENT_BODY TRUE
J 0
(-2450 2975);
DISPLAY 0.872340 (-2450 2975);
PAINT GREEN (-2450 2975);
DISPLAY INVISIBLE (-2450 2975);
FORCEPROP 2 LAST PATH I21
J 0
(-2525 3150);
DISPLAY 1.021277 (-2525 3150);
DISPLAY INVISIBLE (-2525 3150);
FORCEADD OFFPAGE..1
(-2575 3175);
FORCEPROP 2 LAST $XR1 91 
J 0
(-2886 3175);
DISPLAY 0.638298 (-2886 3175);
PAINT MONO (-2886 3175);
FORCEPROP 2 LAST $XR0 24 
J 0
(-2796 3175);
DISPLAY 0.638298 (-2796 3175);
PAINT MONO (-2796 3175);
FORCEPROP 2 LAST CDS_LIB standard
J 0
(-2575 3175);
PAINT MONO (-2575 3175);
DISPLAY INVISIBLE (-2575 3175);
FORCEPROP 1 LAST OFFPAGE TRUE
J 0
(-2250 3050);
DISPLAY 0.872340 (-2250 3050);
DISPLAY INVISIBLE (-2250 3050);
FORCEPROP 1 LAST COMMENT_BODY TRUE
J 0
(-2450 3075);
DISPLAY 0.872340 (-2450 3075);
PAINT GREEN (-2450 3075);
DISPLAY INVISIBLE (-2450 3075);
FORCEPROP 2 LAST PATH I22
J 0
(-2525 3250);
DISPLAY 1.021277 (-2525 3250);
DISPLAY INVISIBLE (-2525 3250);
FORCEADD OFFPAGE..1
(-2575 3225);
FORCEPROP 2 LAST $XR1 91 
J 0
(-2886 3225);
DISPLAY 0.638298 (-2886 3225);
PAINT MONO (-2886 3225);
FORCEPROP 2 LAST $XR0 24 
J 0
(-2796 3225);
DISPLAY 0.638298 (-2796 3225);
PAINT MONO (-2796 3225);
FORCEPROP 2 LAST CDS_LIB standard
J 0
(-2575 3225);
PAINT MONO (-2575 3225);
DISPLAY INVISIBLE (-2575 3225);
FORCEPROP 1 LAST OFFPAGE TRUE
J 0
(-2250 3100);
DISPLAY 0.872340 (-2250 3100);
DISPLAY INVISIBLE (-2250 3100);
FORCEPROP 1 LAST COMMENT_BODY TRUE
J 0
(-2450 3125);
DISPLAY 0.872340 (-2450 3125);
PAINT GREEN (-2450 3125);
DISPLAY INVISIBLE (-2450 3125);
FORCEPROP 2 LAST PATH I23
J 0
(-2525 3300);
DISPLAY 1.021277 (-2525 3300);
DISPLAY INVISIBLE (-2525 3300);
FORCEADD OFFPAGE..1
(-2575 3650);
FORCEPROP 2 LAST $XR1 91 
J 0
(-2886 3650);
DISPLAY 0.638298 (-2886 3650);
PAINT MONO (-2886 3650);
FORCEPROP 2 LAST $XR0 24 
J 0
(-2796 3650);
DISPLAY 0.638298 (-2796 3650);
PAINT MONO (-2796 3650);
FORCEPROP 2 LAST CDS_LIB standard
J 0
(-2575 3650);
PAINT MONO (-2575 3650);
DISPLAY INVISIBLE (-2575 3650);
FORCEPROP 1 LAST OFFPAGE TRUE
J 0
(-2250 3525);
DISPLAY 0.872340 (-2250 3525);
DISPLAY INVISIBLE (-2250 3525);
FORCEPROP 1 LAST COMMENT_BODY TRUE
J 0
(-2450 3550);
DISPLAY 0.872340 (-2450 3550);
PAINT GREEN (-2450 3550);
DISPLAY INVISIBLE (-2450 3550);
FORCEPROP 2 LAST PATH I24
J 0
(-2525 3725);
DISPLAY 1.021277 (-2525 3725);
DISPLAY INVISIBLE (-2525 3725);
FORCEADD TAP..1
R 2
(-1650 1875);
FORCEPROP 3 LASTPIN (-1600 1875) SIG_NAME M_E_CPU0_SB_CB<1>
J 0
(-1590 1885);
DISPLAY 0.659574 (-1590 1885);
PAINT MONO (-1590 1885);
DISPLAY INVISIBLE (-1590 1885);
FORCEPROP 1 LASTPIN (-1600 1875) BN 1
J 2
(-1588 1883);
DISPLAY 0.680851 (-1588 1883);
PAINT GREEN (-1588 1883);
FORCEPROP 2 LAST CDS_LIB standard
J 0
(-1650 1875);
DISPLAY INVISIBLE (-1650 1875);
FORCEPROP 1 LAST BODY_TYPE PLUMBING
J 2
(-1650 1925);
DISPLAY 0.872340 (-1650 1925);
PAINT GREEN (-1650 1925);
DISPLAY INVISIBLE (-1650 1925);
FORCEPROP 1 LAST HDL_TAP TRUE
J 2
(-1975 1750);
DISPLAY 0.872340 (-1975 1750);
DISPLAY INVISIBLE (-1975 1750);
FORCEPROP 1 LAST PATH I25
J 2
(-1648 1875);
DISPLAY 0.872340 (-1648 1875);
PAINT GREEN (-1648 1875);
DISPLAY INVISIBLE (-1648 1875);
FORCEADD TAP..1
R 2
(-1650 1825);
FORCEPROP 3 LASTPIN (-1600 1825) SIG_NAME M_E_CPU0_SB_CB<0>
J 0
(-1590 1835);
DISPLAY 0.659574 (-1590 1835);
PAINT MONO (-1590 1835);
DISPLAY INVISIBLE (-1590 1835);
FORCEPROP 1 LASTPIN (-1600 1825) BN 0
J 2
(-1588 1833);
DISPLAY 0.680851 (-1588 1833);
PAINT GREEN (-1588 1833);
FORCEPROP 2 LAST CDS_LIB standard
J 0
(-1650 1825);
PAINT MONO (-1650 1825);
DISPLAY INVISIBLE (-1650 1825);
FORCEPROP 1 LAST BODY_TYPE PLUMBING
J 2
(-1650 1875);
DISPLAY 0.872340 (-1650 1875);
PAINT GREEN (-1650 1875);
DISPLAY INVISIBLE (-1650 1875);
FORCEPROP 1 LAST HDL_TAP TRUE
J 2
(-1975 1700);
DISPLAY 0.872340 (-1975 1700);
DISPLAY INVISIBLE (-1975 1700);
FORCEPROP 1 LAST PATH I26
J 2
(-1648 1825);
DISPLAY 0.872340 (-1648 1825);
PAINT GREEN (-1648 1825);
DISPLAY INVISIBLE (-1648 1825);
FORCEADD TAP..1
R 2
(-1650 1925);
FORCEPROP 3 LASTPIN (-1600 1925) SIG_NAME M_E_CPU0_SB_CB<2>
J 0
(-1590 1935);
DISPLAY 0.659574 (-1590 1935);
PAINT MONO (-1590 1935);
DISPLAY INVISIBLE (-1590 1935);
FORCEPROP 1 LASTPIN (-1600 1925) BN 2
J 2
(-1588 1933);
DISPLAY 0.680851 (-1588 1933);
PAINT GREEN (-1588 1933);
FORCEPROP 2 LAST CDS_LIB standard
J 0
(-1650 1925);
DISPLAY INVISIBLE (-1650 1925);
FORCEPROP 1 LAST BODY_TYPE PLUMBING
J 2
(-1650 1975);
DISPLAY 0.872340 (-1650 1975);
PAINT GREEN (-1650 1975);
DISPLAY INVISIBLE (-1650 1975);
FORCEPROP 1 LAST HDL_TAP TRUE
J 2
(-1975 1800);
DISPLAY 0.872340 (-1975 1800);
DISPLAY INVISIBLE (-1975 1800);
FORCEPROP 1 LAST PATH I27
J 2
(-1648 1925);
DISPLAY 0.872340 (-1648 1925);
PAINT GREEN (-1648 1925);
DISPLAY INVISIBLE (-1648 1925);
FORCEADD TAP..1
R 2
(-1650 1975);
FORCEPROP 3 LASTPIN (-1600 1975) SIG_NAME M_E_CPU0_SB_CB<3>
J 0
(-1590 1985);
DISPLAY 0.659574 (-1590 1985);
PAINT MONO (-1590 1985);
DISPLAY INVISIBLE (-1590 1985);
FORCEPROP 1 LASTPIN (-1600 1975) BN 3
J 2
(-1588 1983);
DISPLAY 0.680851 (-1588 1983);
PAINT GREEN (-1588 1983);
FORCEPROP 2 LAST CDS_LIB standard
J 0
(-1650 1975);
DISPLAY INVISIBLE (-1650 1975);
FORCEPROP 1 LAST BODY_TYPE PLUMBING
J 2
(-1650 2025);
DISPLAY 0.872340 (-1650 2025);
PAINT GREEN (-1650 2025);
DISPLAY INVISIBLE (-1650 2025);
FORCEPROP 1 LAST HDL_TAP TRUE
J 2
(-1975 1850);
DISPLAY 0.872340 (-1975 1850);
DISPLAY INVISIBLE (-1975 1850);
FORCEPROP 1 LAST PATH I28
J 2
(-1648 1975);
DISPLAY 0.872340 (-1648 1975);
PAINT GREEN (-1648 1975);
DISPLAY INVISIBLE (-1648 1975);
FORCEADD TAP..1
R 2
(-1650 2025);
FORCEPROP 3 LASTPIN (-1600 2025) SIG_NAME M_E_CPU0_SB_CB<4>
J 0
(-1590 2035);
DISPLAY 0.659574 (-1590 2035);
PAINT MONO (-1590 2035);
DISPLAY INVISIBLE (-1590 2035);
FORCEPROP 1 LASTPIN (-1600 2025) BN 4
J 2
(-1588 2033);
DISPLAY 0.680851 (-1588 2033);
PAINT GREEN (-1588 2033);
FORCEPROP 2 LAST CDS_LIB standard
J 0
(-1650 2025);
DISPLAY INVISIBLE (-1650 2025);
FORCEPROP 1 LAST BODY_TYPE PLUMBING
J 2
(-1650 2075);
DISPLAY 0.872340 (-1650 2075);
PAINT GREEN (-1650 2075);
DISPLAY INVISIBLE (-1650 2075);
FORCEPROP 1 LAST HDL_TAP TRUE
J 2
(-1975 1900);
DISPLAY 0.872340 (-1975 1900);
DISPLAY INVISIBLE (-1975 1900);
FORCEPROP 1 LAST PATH I29
J 2
(-1648 2025);
DISPLAY 0.872340 (-1648 2025);
PAINT GREEN (-1648 2025);
DISPLAY INVISIBLE (-1648 2025);
FORCEADD OFFPAGE..2
R 2
(-2575 575);
FORCEPROP 2 LAST $XR0 24 
J 0
(-2799 575);
DISPLAY 0.638298 (-2799 575);
PAINT MONO (-2799 575);
FORCEPROP 2 LAST CDS_LIB standard
J 0
(-2575 575);
PAINT MONO (-2575 575);
DISPLAY INVISIBLE (-2575 575);
FORCEPROP 1 LAST OFFPAGE TRUE
J 2
(-2900 450);
DISPLAY 0.872340 (-2900 450);
DISPLAY INVISIBLE (-2900 450);
FORCEPROP 1 LAST COMMENT_BODY TRUE
J 2
(-2530 480);
DISPLAY 0.872340 (-2530 480);
PAINT GREEN (-2530 480);
DISPLAY INVISIBLE (-2530 480);
FORCEPROP 2 LAST PATH I3
J 0
(-2525 650);
DISPLAY 1.021277 (-2525 650);
DISPLAY INVISIBLE (-2525 650);
FORCEADD TAP..1
R 2
(-1650 2125);
FORCEPROP 3 LASTPIN (-1600 2125) SIG_NAME M_E_CPU0_SB_CB<6>
J 0
(-1590 2135);
DISPLAY 0.659574 (-1590 2135);
PAINT MONO (-1590 2135);
DISPLAY INVISIBLE (-1590 2135);
FORCEPROP 1 LASTPIN (-1600 2125) BN 6
J 2
(-1588 2133);
DISPLAY 0.680851 (-1588 2133);
PAINT GREEN (-1588 2133);
FORCEPROP 2 LAST CDS_LIB standard
J 0
(-1650 2125);
DISPLAY INVISIBLE (-1650 2125);
FORCEPROP 1 LAST BODY_TYPE PLUMBING
J 2
(-1650 2175);
DISPLAY 0.872340 (-1650 2175);
PAINT GREEN (-1650 2175);
DISPLAY INVISIBLE (-1650 2175);
FORCEPROP 1 LAST HDL_TAP TRUE
J 2
(-1975 2000);
DISPLAY 0.872340 (-1975 2000);
DISPLAY INVISIBLE (-1975 2000);
FORCEPROP 1 LAST PATH I30
J 2
(-1648 2125);
DISPLAY 0.872340 (-1648 2125);
PAINT GREEN (-1648 2125);
DISPLAY INVISIBLE (-1648 2125);
FORCEADD TAP..1
R 2
(-1650 2075);
FORCEPROP 3 LASTPIN (-1600 2075) SIG_NAME M_E_CPU0_SB_CB<5>
J 0
(-1590 2085);
DISPLAY 0.659574 (-1590 2085);
PAINT MONO (-1590 2085);
DISPLAY INVISIBLE (-1590 2085);
FORCEPROP 1 LASTPIN (-1600 2075) BN 5
J 2
(-1588 2083);
DISPLAY 0.680851 (-1588 2083);
PAINT GREEN (-1588 2083);
FORCEPROP 2 LAST CDS_LIB standard
J 0
(-1650 2075);
DISPLAY INVISIBLE (-1650 2075);
FORCEPROP 1 LAST BODY_TYPE PLUMBING
J 2
(-1650 2125);
DISPLAY 0.872340 (-1650 2125);
PAINT GREEN (-1650 2125);
DISPLAY INVISIBLE (-1650 2125);
FORCEPROP 1 LAST HDL_TAP TRUE
J 2
(-1975 1950);
DISPLAY 0.872340 (-1975 1950);
DISPLAY INVISIBLE (-1975 1950);
FORCEPROP 1 LAST PATH I31
J 2
(-1648 2075);
DISPLAY 0.872340 (-1648 2075);
PAINT GREEN (-1648 2075);
DISPLAY INVISIBLE (-1648 2075);
FORCEADD TAP..1
R 2
(-1650 2175);
FORCEPROP 3 LASTPIN (-1600 2175) SIG_NAME M_E_CPU0_SB_CB<7>
J 0
(-1590 2185);
DISPLAY 0.659574 (-1590 2185);
PAINT MONO (-1590 2185);
DISPLAY INVISIBLE (-1590 2185);
FORCEPROP 1 LASTPIN (-1600 2175) BN 7
J 2
(-1588 2183);
DISPLAY 0.680851 (-1588 2183);
PAINT GREEN (-1588 2183);
FORCEPROP 2 LAST CDS_LIB standard
J 0
(-1650 2175);
DISPLAY INVISIBLE (-1650 2175);
FORCEPROP 1 LAST BODY_TYPE PLUMBING
J 2
(-1650 2225);
DISPLAY 0.872340 (-1650 2225);
PAINT GREEN (-1650 2225);
DISPLAY INVISIBLE (-1650 2225);
FORCEPROP 1 LAST HDL_TAP TRUE
J 2
(-1975 2050);
DISPLAY 0.872340 (-1975 2050);
DISPLAY INVISIBLE (-1975 2050);
FORCEPROP 1 LAST PATH I32
J 2
(-1648 2175);
DISPLAY 0.872340 (-1648 2175);
PAINT GREEN (-1648 2175);
DISPLAY INVISIBLE (-1648 2175);
FORCEADD TAP..1
R 2
(-1650 2275);
FORCEPROP 3 LASTPIN (-1600 2275) SIG_NAME M_E_CPU0_SA_CB<0>
J 0
(-1590 2285);
DISPLAY 0.659574 (-1590 2285);
PAINT MONO (-1590 2285);
DISPLAY INVISIBLE (-1590 2285);
FORCEPROP 1 LASTPIN (-1600 2275) BN 0
J 2
(-1588 2283);
DISPLAY 0.680851 (-1588 2283);
PAINT GREEN (-1588 2283);
FORCEPROP 2 LAST CDS_LIB standard
J 0
(-1650 2275);
PAINT MONO (-1650 2275);
DISPLAY INVISIBLE (-1650 2275);
FORCEPROP 1 LAST BODY_TYPE PLUMBING
J 2
(-1650 2325);
DISPLAY 0.872340 (-1650 2325);
PAINT GREEN (-1650 2325);
DISPLAY INVISIBLE (-1650 2325);
FORCEPROP 1 LAST HDL_TAP TRUE
J 2
(-1975 2150);
DISPLAY 0.872340 (-1975 2150);
DISPLAY INVISIBLE (-1975 2150);
FORCEPROP 1 LAST PATH I33
J 2
(-1648 2275);
DISPLAY 0.872340 (-1648 2275);
PAINT GREEN (-1648 2275);
DISPLAY INVISIBLE (-1648 2275);
FORCEADD TAP..1
R 2
(-1650 2325);
FORCEPROP 3 LASTPIN (-1600 2325) SIG_NAME M_E_CPU0_SA_CB<1>
J 0
(-1590 2335);
DISPLAY 0.659574 (-1590 2335);
PAINT MONO (-1590 2335);
DISPLAY INVISIBLE (-1590 2335);
FORCEPROP 1 LASTPIN (-1600 2325) BN 1
J 2
(-1588 2333);
DISPLAY 0.680851 (-1588 2333);
PAINT GREEN (-1588 2333);
FORCEPROP 2 LAST CDS_LIB standard
J 0
(-1650 2325);
DISPLAY INVISIBLE (-1650 2325);
FORCEPROP 1 LAST BODY_TYPE PLUMBING
J 2
(-1650 2375);
DISPLAY 0.872340 (-1650 2375);
PAINT GREEN (-1650 2375);
DISPLAY INVISIBLE (-1650 2375);
FORCEPROP 1 LAST HDL_TAP TRUE
J 2
(-1975 2200);
DISPLAY 0.872340 (-1975 2200);
DISPLAY INVISIBLE (-1975 2200);
FORCEPROP 1 LAST PATH I34
J 2
(-1648 2325);
DISPLAY 0.872340 (-1648 2325);
PAINT GREEN (-1648 2325);
DISPLAY INVISIBLE (-1648 2325);
FORCEADD TAP..1
R 2
(-1650 2375);
FORCEPROP 3 LASTPIN (-1600 2375) SIG_NAME M_E_CPU0_SA_CB<2>
J 0
(-1590 2385);
DISPLAY 0.659574 (-1590 2385);
PAINT MONO (-1590 2385);
DISPLAY INVISIBLE (-1590 2385);
FORCEPROP 1 LASTPIN (-1600 2375) BN 2
J 2
(-1588 2383);
DISPLAY 0.680851 (-1588 2383);
PAINT GREEN (-1588 2383);
FORCEPROP 2 LAST CDS_LIB standard
J 0
(-1650 2375);
DISPLAY INVISIBLE (-1650 2375);
FORCEPROP 1 LAST BODY_TYPE PLUMBING
J 2
(-1650 2425);
DISPLAY 0.872340 (-1650 2425);
PAINT GREEN (-1650 2425);
DISPLAY INVISIBLE (-1650 2425);
FORCEPROP 1 LAST HDL_TAP TRUE
J 2
(-1975 2250);
DISPLAY 0.872340 (-1975 2250);
DISPLAY INVISIBLE (-1975 2250);
FORCEPROP 1 LAST PATH I35
J 2
(-1648 2375);
DISPLAY 0.872340 (-1648 2375);
PAINT GREEN (-1648 2375);
DISPLAY INVISIBLE (-1648 2375);
FORCEADD TAP..1
R 2
(-1650 2425);
FORCEPROP 3 LASTPIN (-1600 2425) SIG_NAME M_E_CPU0_SA_CB<3>
J 0
(-1590 2435);
DISPLAY 0.659574 (-1590 2435);
PAINT MONO (-1590 2435);
DISPLAY INVISIBLE (-1590 2435);
FORCEPROP 1 LASTPIN (-1600 2425) BN 3
J 2
(-1588 2433);
DISPLAY 0.680851 (-1588 2433);
PAINT GREEN (-1588 2433);
FORCEPROP 2 LAST CDS_LIB standard
J 0
(-1650 2425);
DISPLAY INVISIBLE (-1650 2425);
FORCEPROP 1 LAST BODY_TYPE PLUMBING
J 2
(-1650 2475);
DISPLAY 0.872340 (-1650 2475);
PAINT GREEN (-1650 2475);
DISPLAY INVISIBLE (-1650 2475);
FORCEPROP 1 LAST HDL_TAP TRUE
J 2
(-1975 2300);
DISPLAY 0.872340 (-1975 2300);
DISPLAY INVISIBLE (-1975 2300);
FORCEPROP 1 LAST PATH I36
J 2
(-1648 2425);
DISPLAY 0.872340 (-1648 2425);
PAINT GREEN (-1648 2425);
DISPLAY INVISIBLE (-1648 2425);
FORCEADD TAP..1
R 2
(-1650 2475);
FORCEPROP 3 LASTPIN (-1600 2475) SIG_NAME M_E_CPU0_SA_CB<4>
J 0
(-1590 2485);
DISPLAY 0.659574 (-1590 2485);
PAINT MONO (-1590 2485);
DISPLAY INVISIBLE (-1590 2485);
FORCEPROP 1 LASTPIN (-1600 2475) BN 4
J 2
(-1588 2483);
DISPLAY 0.680851 (-1588 2483);
PAINT GREEN (-1588 2483);
FORCEPROP 2 LAST CDS_LIB standard
J 0
(-1650 2475);
DISPLAY INVISIBLE (-1650 2475);
FORCEPROP 1 LAST BODY_TYPE PLUMBING
J 2
(-1650 2525);
DISPLAY 0.872340 (-1650 2525);
PAINT GREEN (-1650 2525);
DISPLAY INVISIBLE (-1650 2525);
FORCEPROP 1 LAST HDL_TAP TRUE
J 2
(-1975 2350);
DISPLAY 0.872340 (-1975 2350);
DISPLAY INVISIBLE (-1975 2350);
FORCEPROP 1 LAST PATH I37
J 2
(-1648 2475);
DISPLAY 0.872340 (-1648 2475);
PAINT GREEN (-1648 2475);
DISPLAY INVISIBLE (-1648 2475);
FORCEADD TAP..1
R 2
(-1650 2525);
FORCEPROP 3 LASTPIN (-1600 2525) SIG_NAME M_E_CPU0_SA_CB<5>
J 0
(-1590 2535);
DISPLAY 0.659574 (-1590 2535);
PAINT MONO (-1590 2535);
DISPLAY INVISIBLE (-1590 2535);
FORCEPROP 1 LASTPIN (-1600 2525) BN 5
J 2
(-1588 2533);
DISPLAY 0.680851 (-1588 2533);
PAINT GREEN (-1588 2533);
FORCEPROP 2 LAST CDS_LIB standard
J 0
(-1650 2525);
DISPLAY INVISIBLE (-1650 2525);
FORCEPROP 1 LAST BODY_TYPE PLUMBING
J 2
(-1650 2575);
DISPLAY 0.872340 (-1650 2575);
PAINT GREEN (-1650 2575);
DISPLAY INVISIBLE (-1650 2575);
FORCEPROP 1 LAST HDL_TAP TRUE
J 2
(-1975 2400);
DISPLAY 0.872340 (-1975 2400);
DISPLAY INVISIBLE (-1975 2400);
FORCEPROP 1 LAST PATH I38
J 2
(-1648 2525);
DISPLAY 0.872340 (-1648 2525);
PAINT GREEN (-1648 2525);
DISPLAY INVISIBLE (-1648 2525);
FORCEADD TAP..1
R 2
(-1650 2625);
FORCEPROP 3 LASTPIN (-1600 2625) SIG_NAME M_E_CPU0_SA_CB<7>
J 0
(-1590 2635);
DISPLAY 0.659574 (-1590 2635);
PAINT MONO (-1590 2635);
DISPLAY INVISIBLE (-1590 2635);
FORCEPROP 1 LASTPIN (-1600 2625) BN 7
J 2
(-1588 2633);
DISPLAY 0.680851 (-1588 2633);
PAINT GREEN (-1588 2633);
FORCEPROP 2 LAST CDS_LIB standard
J 0
(-1650 2625);
DISPLAY INVISIBLE (-1650 2625);
FORCEPROP 1 LAST BODY_TYPE PLUMBING
J 2
(-1650 2675);
DISPLAY 0.872340 (-1650 2675);
PAINT GREEN (-1650 2675);
DISPLAY INVISIBLE (-1650 2675);
FORCEPROP 1 LAST HDL_TAP TRUE
J 2
(-1975 2500);
DISPLAY 0.872340 (-1975 2500);
DISPLAY INVISIBLE (-1975 2500);
FORCEPROP 1 LAST PATH I39
J 2
(-1648 2625);
DISPLAY 0.872340 (-1648 2625);
PAINT GREEN (-1648 2625);
DISPLAY INVISIBLE (-1648 2625);
FORCEADD OFFPAGE..2
R 2
(-2575 625);
FORCEPROP 2 LAST $XR0 24 
J 0
(-2799 625);
DISPLAY 0.638298 (-2799 625);
PAINT MONO (-2799 625);
FORCEPROP 2 LAST CDS_LIB standard
J 0
(-2575 625);
PAINT MONO (-2575 625);
DISPLAY INVISIBLE (-2575 625);
FORCEPROP 1 LAST OFFPAGE TRUE
J 2
(-2900 500);
DISPLAY 0.872340 (-2900 500);
DISPLAY INVISIBLE (-2900 500);
FORCEPROP 1 LAST COMMENT_BODY TRUE
J 2
(-2530 530);
DISPLAY 0.872340 (-2530 530);
PAINT GREEN (-2530 530);
DISPLAY INVISIBLE (-2530 530);
FORCEPROP 2 LAST PATH I4
J 0
(-2525 700);
DISPLAY 1.021277 (-2525 700);
DISPLAY INVISIBLE (-2525 700);
FORCEADD TAP..1
R 2
(-1650 2575);
FORCEPROP 3 LASTPIN (-1600 2575) SIG_NAME M_E_CPU0_SA_CB<6>
J 0
(-1590 2585);
DISPLAY 0.659574 (-1590 2585);
PAINT MONO (-1590 2585);
DISPLAY INVISIBLE (-1590 2585);
FORCEPROP 1 LASTPIN (-1600 2575) BN 6
J 2
(-1588 2583);
DISPLAY 0.680851 (-1588 2583);
PAINT GREEN (-1588 2583);
FORCEPROP 2 LAST CDS_LIB standard
J 0
(-1650 2575);
DISPLAY INVISIBLE (-1650 2575);
FORCEPROP 1 LAST BODY_TYPE PLUMBING
J 2
(-1650 2625);
DISPLAY 0.872340 (-1650 2625);
PAINT GREEN (-1650 2625);
DISPLAY INVISIBLE (-1650 2625);
FORCEPROP 1 LAST HDL_TAP TRUE
J 2
(-1975 2450);
DISPLAY 0.872340 (-1975 2450);
DISPLAY INVISIBLE (-1975 2450);
FORCEPROP 1 LAST PATH I40
J 2
(-1648 2575);
DISPLAY 0.872340 (-1648 2575);
PAINT GREEN (-1648 2575);
DISPLAY INVISIBLE (-1648 2575);
FORCEADD TAP..1
R 2
(-1650 3325);
FORCEPROP 3 LASTPIN (-1600 3325) SIG_NAME M_E_CPU0_SB_CA<0>
J 0
(-1590 3335);
DISPLAY 0.659574 (-1590 3335);
PAINT MONO (-1590 3335);
DISPLAY INVISIBLE (-1590 3335);
FORCEPROP 1 LASTPIN (-1600 3325) BN 0
J 2
(-1588 3333);
DISPLAY 0.680851 (-1588 3333);
PAINT GREEN (-1588 3333);
FORCEPROP 2 LAST CDS_LIB standard
J 0
(-1650 3325);
DISPLAY INVISIBLE (-1650 3325);
FORCEPROP 1 LAST BODY_TYPE PLUMBING
J 2
(-1650 3375);
DISPLAY 0.872340 (-1650 3375);
PAINT GREEN (-1650 3375);
DISPLAY INVISIBLE (-1650 3375);
FORCEPROP 1 LAST HDL_TAP TRUE
J 2
(-1975 3200);
DISPLAY 0.872340 (-1975 3200);
DISPLAY INVISIBLE (-1975 3200);
FORCEPROP 1 LAST PATH I41
J 2
(-1648 3325);
DISPLAY 0.872340 (-1648 3325);
PAINT GREEN (-1648 3325);
DISPLAY INVISIBLE (-1648 3325);
FORCEADD TAP..1
R 2
(-1650 3375);
FORCEPROP 3 LASTPIN (-1600 3375) SIG_NAME M_E_CPU0_SB_CA<1>
J 0
(-1590 3385);
DISPLAY 0.659574 (-1590 3385);
PAINT MONO (-1590 3385);
DISPLAY INVISIBLE (-1590 3385);
FORCEPROP 1 LASTPIN (-1600 3375) BN 1
J 2
(-1588 3383);
DISPLAY 0.680851 (-1588 3383);
PAINT GREEN (-1588 3383);
FORCEPROP 2 LAST CDS_LIB standard
J 0
(-1650 3375);
DISPLAY INVISIBLE (-1650 3375);
FORCEPROP 1 LAST BODY_TYPE PLUMBING
J 2
(-1650 3425);
DISPLAY 0.872340 (-1650 3425);
PAINT GREEN (-1650 3425);
DISPLAY INVISIBLE (-1650 3425);
FORCEPROP 1 LAST HDL_TAP TRUE
J 2
(-1975 3250);
DISPLAY 0.872340 (-1975 3250);
DISPLAY INVISIBLE (-1975 3250);
FORCEPROP 1 LAST PATH I42
J 2
(-1648 3375);
DISPLAY 0.872340 (-1648 3375);
PAINT GREEN (-1648 3375);
DISPLAY INVISIBLE (-1648 3375);
FORCEADD TAP..1
R 2
(-1650 3425);
FORCEPROP 3 LASTPIN (-1600 3425) SIG_NAME M_E_CPU0_SB_CA<2>
J 0
(-1590 3435);
DISPLAY 0.659574 (-1590 3435);
PAINT MONO (-1590 3435);
DISPLAY INVISIBLE (-1590 3435);
FORCEPROP 1 LASTPIN (-1600 3425) BN 2
J 2
(-1588 3433);
DISPLAY 0.680851 (-1588 3433);
PAINT GREEN (-1588 3433);
FORCEPROP 2 LAST CDS_LIB standard
J 0
(-1650 3425);
DISPLAY INVISIBLE (-1650 3425);
FORCEPROP 1 LAST BODY_TYPE PLUMBING
J 2
(-1650 3475);
DISPLAY 0.872340 (-1650 3475);
PAINT GREEN (-1650 3475);
DISPLAY INVISIBLE (-1650 3475);
FORCEPROP 1 LAST HDL_TAP TRUE
J 2
(-1975 3300);
DISPLAY 0.872340 (-1975 3300);
DISPLAY INVISIBLE (-1975 3300);
FORCEPROP 1 LAST PATH I43
J 2
(-1648 3425);
DISPLAY 0.872340 (-1648 3425);
PAINT GREEN (-1648 3425);
DISPLAY INVISIBLE (-1648 3425);
FORCEADD TAP..1
R 2
(-1650 3525);
FORCEPROP 3 LASTPIN (-1600 3525) SIG_NAME M_E_CPU0_SB_CA<4>
J 0
(-1590 3535);
DISPLAY 0.659574 (-1590 3535);
PAINT MONO (-1590 3535);
DISPLAY INVISIBLE (-1590 3535);
FORCEPROP 1 LASTPIN (-1600 3525) BN 4
J 2
(-1588 3533);
DISPLAY 0.680851 (-1588 3533);
PAINT GREEN (-1588 3533);
FORCEPROP 2 LAST CDS_LIB standard
J 0
(-1650 3525);
DISPLAY INVISIBLE (-1650 3525);
FORCEPROP 1 LAST BODY_TYPE PLUMBING
J 2
(-1650 3575);
DISPLAY 0.872340 (-1650 3575);
PAINT GREEN (-1650 3575);
DISPLAY INVISIBLE (-1650 3575);
FORCEPROP 1 LAST HDL_TAP TRUE
J 2
(-1975 3400);
DISPLAY 0.872340 (-1975 3400);
DISPLAY INVISIBLE (-1975 3400);
FORCEPROP 1 LAST PATH I44
J 2
(-1648 3525);
DISPLAY 0.872340 (-1648 3525);
PAINT GREEN (-1648 3525);
DISPLAY INVISIBLE (-1648 3525);
FORCEADD TAP..1
R 2
(-1650 3475);
FORCEPROP 3 LASTPIN (-1600 3475) SIG_NAME M_E_CPU0_SB_CA<3>
J 0
(-1590 3485);
DISPLAY 0.659574 (-1590 3485);
PAINT MONO (-1590 3485);
DISPLAY INVISIBLE (-1590 3485);
FORCEPROP 1 LASTPIN (-1600 3475) BN 3
J 2
(-1588 3483);
DISPLAY 0.680851 (-1588 3483);
PAINT GREEN (-1588 3483);
FORCEPROP 2 LAST CDS_LIB standard
J 0
(-1650 3475);
DISPLAY INVISIBLE (-1650 3475);
FORCEPROP 1 LAST BODY_TYPE PLUMBING
J 2
(-1650 3525);
DISPLAY 0.872340 (-1650 3525);
PAINT GREEN (-1650 3525);
DISPLAY INVISIBLE (-1650 3525);
FORCEPROP 1 LAST HDL_TAP TRUE
J 2
(-1975 3350);
DISPLAY 0.872340 (-1975 3350);
DISPLAY INVISIBLE (-1975 3350);
FORCEPROP 1 LAST PATH I45
J 2
(-1648 3475);
DISPLAY 0.872340 (-1648 3475);
PAINT GREEN (-1648 3475);
DISPLAY INVISIBLE (-1648 3475);
FORCEADD TAP..1
R 2
(-1650 3625);
FORCEPROP 3 LASTPIN (-1600 3625) SIG_NAME M_E_CPU0_SB_CA<6>
J 0
(-1590 3635);
DISPLAY 0.659574 (-1590 3635);
PAINT MONO (-1590 3635);
DISPLAY INVISIBLE (-1590 3635);
FORCEPROP 1 LASTPIN (-1600 3625) BN 6
J 2
(-1588 3633);
DISPLAY 0.680851 (-1588 3633);
PAINT GREEN (-1588 3633);
FORCEPROP 2 LAST CDS_LIB standard
J 0
(-1650 3625);
DISPLAY INVISIBLE (-1650 3625);
FORCEPROP 1 LAST BODY_TYPE PLUMBING
J 2
(-1650 3675);
DISPLAY 0.872340 (-1650 3675);
PAINT GREEN (-1650 3675);
DISPLAY INVISIBLE (-1650 3675);
FORCEPROP 1 LAST HDL_TAP TRUE
J 2
(-1975 3500);
DISPLAY 0.872340 (-1975 3500);
DISPLAY INVISIBLE (-1975 3500);
FORCEPROP 1 LAST PATH I46
J 2
(-1648 3625);
DISPLAY 0.872340 (-1648 3625);
PAINT GREEN (-1648 3625);
DISPLAY INVISIBLE (-1648 3625);
FORCEADD TAP..1
R 2
(-1650 3575);
FORCEPROP 3 LASTPIN (-1600 3575) SIG_NAME M_E_CPU0_SB_CA<5>
J 0
(-1590 3585);
DISPLAY 0.659574 (-1590 3585);
PAINT MONO (-1590 3585);
DISPLAY INVISIBLE (-1590 3585);
FORCEPROP 1 LASTPIN (-1600 3575) BN 5
J 2
(-1588 3583);
DISPLAY 0.680851 (-1588 3583);
PAINT GREEN (-1588 3583);
FORCEPROP 2 LAST CDS_LIB standard
J 0
(-1650 3575);
DISPLAY INVISIBLE (-1650 3575);
FORCEPROP 1 LAST BODY_TYPE PLUMBING
J 2
(-1650 3625);
DISPLAY 0.872340 (-1650 3625);
PAINT GREEN (-1650 3625);
DISPLAY INVISIBLE (-1650 3625);
FORCEPROP 1 LAST HDL_TAP TRUE
J 2
(-1975 3450);
DISPLAY 0.872340 (-1975 3450);
DISPLAY INVISIBLE (-1975 3450);
FORCEPROP 1 LAST PATH I47
J 2
(-1648 3575);
DISPLAY 0.872340 (-1648 3575);
PAINT GREEN (-1648 3575);
DISPLAY INVISIBLE (-1648 3575);
FORCEADD TAP..1
R 2
(-1650 3775);
FORCEPROP 3 LASTPIN (-1600 3775) SIG_NAME M_E_CPU0_SA_CA<1>
J 0
(-1590 3785);
DISPLAY 0.659574 (-1590 3785);
PAINT MONO (-1590 3785);
DISPLAY INVISIBLE (-1590 3785);
FORCEPROP 1 LASTPIN (-1600 3775) BN 1
J 2
(-1588 3783);
DISPLAY 0.680851 (-1588 3783);
PAINT GREEN (-1588 3783);
FORCEPROP 2 LAST CDS_LIB standard
J 0
(-1650 3775);
DISPLAY INVISIBLE (-1650 3775);
FORCEPROP 1 LAST BODY_TYPE PLUMBING
J 2
(-1650 3825);
DISPLAY 0.872340 (-1650 3825);
PAINT GREEN (-1650 3825);
DISPLAY INVISIBLE (-1650 3825);
FORCEPROP 1 LAST HDL_TAP TRUE
J 2
(-1975 3650);
DISPLAY 0.872340 (-1975 3650);
DISPLAY INVISIBLE (-1975 3650);
FORCEPROP 1 LAST PATH I48
J 2
(-1648 3775);
DISPLAY 0.872340 (-1648 3775);
PAINT GREEN (-1648 3775);
DISPLAY INVISIBLE (-1648 3775);
FORCEADD TAP..1
R 2
(-1650 3725);
FORCEPROP 3 LASTPIN (-1600 3725) SIG_NAME M_E_CPU0_SA_CA<0>
J 0
(-1590 3735);
DISPLAY 0.659574 (-1590 3735);
PAINT MONO (-1590 3735);
DISPLAY INVISIBLE (-1590 3735);
FORCEPROP 1 LASTPIN (-1600 3725) BN 0
J 2
(-1588 3733);
DISPLAY 0.680851 (-1588 3733);
PAINT GREEN (-1588 3733);
FORCEPROP 2 LAST CDS_LIB standard
J 0
(-1650 3725);
DISPLAY INVISIBLE (-1650 3725);
FORCEPROP 1 LAST BODY_TYPE PLUMBING
J 2
(-1650 3775);
DISPLAY 0.872340 (-1650 3775);
PAINT GREEN (-1650 3775);
DISPLAY INVISIBLE (-1650 3775);
FORCEPROP 1 LAST HDL_TAP TRUE
J 2
(-1975 3600);
DISPLAY 0.872340 (-1975 3600);
DISPLAY INVISIBLE (-1975 3600);
FORCEPROP 1 LAST PATH I49
J 2
(-1648 3725);
DISPLAY 0.872340 (-1648 3725);
PAINT GREEN (-1648 3725);
DISPLAY INVISIBLE (-1648 3725);
FORCEADD OFFPAGE..3
R 2
(-2575 1175);
FORCEPROP 2 LAST $XR0 114 
J 0
(-2855 1175);
DISPLAY 0.638298 (-2855 1175);
PAINT MONO (-2855 1175);
FORCEPROP 2 LAST CDS_LIB standard
J 0
(-2575 1175);
PAINT MONO (-2575 1175);
DISPLAY INVISIBLE (-2575 1175);
FORCEPROP 1 LAST OFFPAGE TRUE
J 2
(-2900 1050);
DISPLAY 0.872340 (-2900 1050);
DISPLAY INVISIBLE (-2900 1050);
FORCEPROP 1 LAST COMMENT_BODY TRUE
J 2
(-2525 1075);
DISPLAY 0.872340 (-2525 1075);
PAINT GREEN (-2525 1075);
DISPLAY INVISIBLE (-2525 1075);
FORCEPROP 2 LAST PATH I5
J 0
(-2525 1250);
DISPLAY 1.021277 (-2525 1250);
DISPLAY INVISIBLE (-2525 1250);
FORCEADD TAP..1
(0 825);
FORCEPROP 3 LASTPIN (-50 825) SIG_NAME M_E_CPU0_SB_DQ<0>
J 0
(-40 835);
DISPLAY 0.659574 (-40 835);
PAINT MONO (-40 835);
DISPLAY INVISIBLE (-40 835);
FORCEPROP 1 LASTPIN (-50 825) BN 0
J 0
(-62 833);
DISPLAY 0.680851 (-62 833);
PAINT GREEN (-62 833);
FORCEPROP 2 LAST CDS_LIB standard
J 0
(0 825);
PAINT MONO (0 825);
DISPLAY INVISIBLE (0 825);
FORCEPROP 1 LAST BODY_TYPE PLUMBING
J 0
(0 875);
DISPLAY 0.872340 (0 875);
PAINT GREEN (0 875);
DISPLAY INVISIBLE (0 875);
FORCEPROP 1 LAST HDL_TAP TRUE
J 0
(325 700);
DISPLAY 0.872340 (325 700);
DISPLAY INVISIBLE (325 700);
FORCEPROP 1 LAST PATH I50
J 0
(-2 825);
DISPLAY 0.872340 (-2 825);
PAINT GREEN (-2 825);
DISPLAY INVISIBLE (-2 825);
FORCEADD TAP..1
(0 875);
FORCEPROP 3 LASTPIN (-50 875) SIG_NAME M_E_CPU0_SB_DQ<1>
J 0
(-40 885);
DISPLAY 0.659574 (-40 885);
PAINT MONO (-40 885);
DISPLAY INVISIBLE (-40 885);
FORCEPROP 1 LASTPIN (-50 875) BN 1
J 0
(-62 883);
DISPLAY 0.680851 (-62 883);
PAINT GREEN (-62 883);
FORCEPROP 2 LAST CDS_LIB standard
J 0
(0 875);
PAINT MONO (0 875);
DISPLAY INVISIBLE (0 875);
FORCEPROP 1 LAST BODY_TYPE PLUMBING
J 0
(0 925);
DISPLAY 0.872340 (0 925);
PAINT GREEN (0 925);
DISPLAY INVISIBLE (0 925);
FORCEPROP 1 LAST HDL_TAP TRUE
J 0
(325 750);
DISPLAY 0.872340 (325 750);
DISPLAY INVISIBLE (325 750);
FORCEPROP 1 LAST PATH I51
J 0
(-2 875);
DISPLAY 0.872340 (-2 875);
PAINT GREEN (-2 875);
DISPLAY INVISIBLE (-2 875);
FORCEADD TAP..1
(0 975);
FORCEPROP 3 LASTPIN (-50 975) SIG_NAME M_E_CPU0_SB_DQ<3>
J 0
(-40 985);
DISPLAY 0.659574 (-40 985);
PAINT MONO (-40 985);
DISPLAY INVISIBLE (-40 985);
FORCEPROP 1 LASTPIN (-50 975) BN 3
J 0
(-62 983);
DISPLAY 0.680851 (-62 983);
PAINT GREEN (-62 983);
FORCEPROP 2 LAST CDS_LIB standard
J 0
(0 975);
PAINT MONO (0 975);
DISPLAY INVISIBLE (0 975);
FORCEPROP 1 LAST BODY_TYPE PLUMBING
J 0
(0 1025);
DISPLAY 0.872340 (0 1025);
PAINT GREEN (0 1025);
DISPLAY INVISIBLE (0 1025);
FORCEPROP 1 LAST HDL_TAP TRUE
J 0
(325 850);
DISPLAY 0.872340 (325 850);
DISPLAY INVISIBLE (325 850);
FORCEPROP 1 LAST PATH I52
J 0
(-2 975);
DISPLAY 0.872340 (-2 975);
PAINT GREEN (-2 975);
DISPLAY INVISIBLE (-2 975);
FORCEADD TAP..1
(0 925);
FORCEPROP 3 LASTPIN (-50 925) SIG_NAME M_E_CPU0_SB_DQ<2>
J 0
(-40 935);
DISPLAY 0.659574 (-40 935);
PAINT MONO (-40 935);
DISPLAY INVISIBLE (-40 935);
FORCEPROP 1 LASTPIN (-50 925) BN 2
J 0
(-62 933);
DISPLAY 0.680851 (-62 933);
PAINT GREEN (-62 933);
FORCEPROP 2 LAST CDS_LIB standard
J 0
(0 925);
PAINT MONO (0 925);
DISPLAY INVISIBLE (0 925);
FORCEPROP 1 LAST BODY_TYPE PLUMBING
J 0
(0 975);
DISPLAY 0.872340 (0 975);
PAINT GREEN (0 975);
DISPLAY INVISIBLE (0 975);
FORCEPROP 1 LAST HDL_TAP TRUE
J 0
(325 800);
DISPLAY 0.872340 (325 800);
DISPLAY INVISIBLE (325 800);
FORCEPROP 1 LAST PATH I53
J 0
(-2 925);
DISPLAY 0.872340 (-2 925);
PAINT GREEN (-2 925);
DISPLAY INVISIBLE (-2 925);
FORCEADD TAP..1
(0 1125);
FORCEPROP 3 LASTPIN (-50 1125) SIG_NAME M_E_CPU0_SB_DQ<6>
J 0
(-40 1135);
DISPLAY 0.659574 (-40 1135);
PAINT MONO (-40 1135);
DISPLAY INVISIBLE (-40 1135);
FORCEPROP 1 LASTPIN (-50 1125) BN 6
J 0
(-62 1133);
DISPLAY 0.680851 (-62 1133);
PAINT GREEN (-62 1133);
FORCEPROP 2 LAST CDS_LIB standard
J 0
(0 1125);
PAINT MONO (0 1125);
DISPLAY INVISIBLE (0 1125);
FORCEPROP 1 LAST BODY_TYPE PLUMBING
J 0
(0 1175);
DISPLAY 0.872340 (0 1175);
PAINT GREEN (0 1175);
DISPLAY INVISIBLE (0 1175);
FORCEPROP 1 LAST HDL_TAP TRUE
J 0
(325 1000);
DISPLAY 0.872340 (325 1000);
DISPLAY INVISIBLE (325 1000);
FORCEPROP 1 LAST PATH I54
J 0
(-2 1125);
DISPLAY 0.872340 (-2 1125);
PAINT GREEN (-2 1125);
DISPLAY INVISIBLE (-2 1125);
FORCEADD TAP..1
(0 1075);
FORCEPROP 3 LASTPIN (-50 1075) SIG_NAME M_E_CPU0_SB_DQ<5>
J 0
(-40 1085);
DISPLAY 0.659574 (-40 1085);
PAINT MONO (-40 1085);
DISPLAY INVISIBLE (-40 1085);
FORCEPROP 1 LASTPIN (-50 1075) BN 5
J 0
(-62 1083);
DISPLAY 0.680851 (-62 1083);
PAINT GREEN (-62 1083);
FORCEPROP 2 LAST CDS_LIB standard
J 0
(0 1075);
PAINT MONO (0 1075);
DISPLAY INVISIBLE (0 1075);
FORCEPROP 1 LAST BODY_TYPE PLUMBING
J 0
(0 1125);
DISPLAY 0.872340 (0 1125);
PAINT GREEN (0 1125);
DISPLAY INVISIBLE (0 1125);
FORCEPROP 1 LAST HDL_TAP TRUE
J 0
(325 950);
DISPLAY 0.872340 (325 950);
DISPLAY INVISIBLE (325 950);
FORCEPROP 1 LAST PATH I55
J 0
(-2 1075);
DISPLAY 0.872340 (-2 1075);
PAINT GREEN (-2 1075);
DISPLAY INVISIBLE (-2 1075);
FORCEADD TAP..1
(0 1025);
FORCEPROP 3 LASTPIN (-50 1025) SIG_NAME M_E_CPU0_SB_DQ<4>
J 0
(-40 1035);
DISPLAY 0.659574 (-40 1035);
PAINT MONO (-40 1035);
DISPLAY INVISIBLE (-40 1035);
FORCEPROP 1 LASTPIN (-50 1025) BN 4
J 0
(-62 1033);
DISPLAY 0.680851 (-62 1033);
PAINT GREEN (-62 1033);
FORCEPROP 2 LAST CDS_LIB standard
J 0
(0 1025);
PAINT MONO (0 1025);
DISPLAY INVISIBLE (0 1025);
FORCEPROP 1 LAST BODY_TYPE PLUMBING
J 0
(0 1075);
DISPLAY 0.872340 (0 1075);
PAINT GREEN (0 1075);
DISPLAY INVISIBLE (0 1075);
FORCEPROP 1 LAST HDL_TAP TRUE
J 0
(325 900);
DISPLAY 0.872340 (325 900);
DISPLAY INVISIBLE (325 900);
FORCEPROP 1 LAST PATH I56
J 0
(-2 1025);
DISPLAY 0.872340 (-2 1025);
PAINT GREEN (-2 1025);
DISPLAY INVISIBLE (-2 1025);
FORCEADD TAP..1
(0 1175);
FORCEPROP 3 LASTPIN (-50 1175) SIG_NAME M_E_CPU0_SB_DQ<7>
J 0
(-40 1185);
DISPLAY 0.659574 (-40 1185);
PAINT MONO (-40 1185);
DISPLAY INVISIBLE (-40 1185);
FORCEPROP 1 LASTPIN (-50 1175) BN 7
J 0
(-62 1183);
DISPLAY 0.680851 (-62 1183);
PAINT GREEN (-62 1183);
FORCEPROP 2 LAST CDS_LIB standard
J 0
(0 1175);
PAINT MONO (0 1175);
DISPLAY INVISIBLE (0 1175);
FORCEPROP 1 LAST BODY_TYPE PLUMBING
J 0
(0 1225);
DISPLAY 0.872340 (0 1225);
PAINT GREEN (0 1225);
DISPLAY INVISIBLE (0 1225);
FORCEPROP 1 LAST HDL_TAP TRUE
J 0
(325 1050);
DISPLAY 0.872340 (325 1050);
DISPLAY INVISIBLE (325 1050);
FORCEPROP 1 LAST PATH I57
J 0
(-2 1175);
DISPLAY 0.872340 (-2 1175);
PAINT GREEN (-2 1175);
DISPLAY INVISIBLE (-2 1175);
FORCEADD TAP..1
(0 1225);
FORCEPROP 3 LASTPIN (-50 1225) SIG_NAME M_E_CPU0_SB_DQ<8>
J 0
(-40 1235);
DISPLAY 0.659574 (-40 1235);
PAINT MONO (-40 1235);
DISPLAY INVISIBLE (-40 1235);
FORCEPROP 1 LASTPIN (-50 1225) BN 8
J 0
(-62 1233);
DISPLAY 0.680851 (-62 1233);
PAINT GREEN (-62 1233);
FORCEPROP 2 LAST CDS_LIB standard
J 0
(0 1225);
PAINT MONO (0 1225);
DISPLAY INVISIBLE (0 1225);
FORCEPROP 1 LAST BODY_TYPE PLUMBING
J 0
(0 1275);
DISPLAY 0.872340 (0 1275);
PAINT GREEN (0 1275);
DISPLAY INVISIBLE (0 1275);
FORCEPROP 1 LAST HDL_TAP TRUE
J 0
(325 1100);
DISPLAY 0.872340 (325 1100);
DISPLAY INVISIBLE (325 1100);
FORCEPROP 1 LAST PATH I58
J 0
(-2 1225);
DISPLAY 0.872340 (-2 1225);
PAINT GREEN (-2 1225);
DISPLAY INVISIBLE (-2 1225);
FORCEADD TAP..1
(0 1275);
FORCEPROP 3 LASTPIN (-50 1275) SIG_NAME M_E_CPU0_SB_DQ<9>
J 0
(-40 1285);
DISPLAY 0.659574 (-40 1285);
PAINT MONO (-40 1285);
DISPLAY INVISIBLE (-40 1285);
FORCEPROP 1 LASTPIN (-50 1275) BN 9
J 0
(-62 1283);
DISPLAY 0.680851 (-62 1283);
PAINT GREEN (-62 1283);
FORCEPROP 2 LAST CDS_LIB standard
J 0
(0 1275);
PAINT MONO (0 1275);
DISPLAY INVISIBLE (0 1275);
FORCEPROP 1 LAST BODY_TYPE PLUMBING
J 0
(0 1325);
DISPLAY 0.872340 (0 1325);
PAINT GREEN (0 1325);
DISPLAY INVISIBLE (0 1325);
FORCEPROP 1 LAST HDL_TAP TRUE
J 0
(325 1150);
DISPLAY 0.872340 (325 1150);
DISPLAY INVISIBLE (325 1150);
FORCEPROP 1 LAST PATH I59
J 0
(-2 1275);
DISPLAY 0.872340 (-2 1275);
PAINT GREEN (-2 1275);
DISPLAY INVISIBLE (-2 1275);
FORCEADD TAP..1
(0 1325);
FORCEPROP 3 LASTPIN (-50 1325) SIG_NAME M_E_CPU0_SB_DQ<10>
J 0
(-40 1335);
DISPLAY 0.659574 (-40 1335);
PAINT MONO (-40 1335);
DISPLAY INVISIBLE (-40 1335);
FORCEPROP 1 LASTPIN (-50 1325) BN 10
J 0
(-62 1333);
DISPLAY 0.680851 (-62 1333);
PAINT GREEN (-62 1333);
FORCEPROP 2 LAST CDS_LIB standard
J 0
(0 1325);
PAINT MONO (0 1325);
DISPLAY INVISIBLE (0 1325);
FORCEPROP 1 LAST BODY_TYPE PLUMBING
J 0
(0 1375);
DISPLAY 0.872340 (0 1375);
PAINT GREEN (0 1375);
DISPLAY INVISIBLE (0 1375);
FORCEPROP 1 LAST HDL_TAP TRUE
J 0
(325 1200);
DISPLAY 0.872340 (325 1200);
DISPLAY INVISIBLE (325 1200);
FORCEPROP 1 LAST PATH I60
J 0
(-2 1325);
DISPLAY 0.872340 (-2 1325);
PAINT GREEN (-2 1325);
DISPLAY INVISIBLE (-2 1325);
FORCEADD TAP..1
(0 1375);
FORCEPROP 3 LASTPIN (-50 1375) SIG_NAME M_E_CPU0_SB_DQ<11>
J 0
(-40 1385);
DISPLAY 0.659574 (-40 1385);
PAINT MONO (-40 1385);
DISPLAY INVISIBLE (-40 1385);
FORCEPROP 1 LASTPIN (-50 1375) BN 11
J 0
(-62 1383);
DISPLAY 0.680851 (-62 1383);
PAINT GREEN (-62 1383);
FORCEPROP 2 LAST CDS_LIB standard
J 0
(0 1375);
PAINT MONO (0 1375);
DISPLAY INVISIBLE (0 1375);
FORCEPROP 1 LAST BODY_TYPE PLUMBING
J 0
(0 1425);
DISPLAY 0.872340 (0 1425);
PAINT GREEN (0 1425);
DISPLAY INVISIBLE (0 1425);
FORCEPROP 1 LAST HDL_TAP TRUE
J 0
(325 1250);
DISPLAY 0.872340 (325 1250);
DISPLAY INVISIBLE (325 1250);
FORCEPROP 1 LAST PATH I61
J 0
(-2 1375);
DISPLAY 0.872340 (-2 1375);
PAINT GREEN (-2 1375);
DISPLAY INVISIBLE (-2 1375);
FORCEADD TAP..1
(0 1425);
FORCEPROP 3 LASTPIN (-50 1425) SIG_NAME M_E_CPU0_SB_DQ<12>
J 0
(-40 1435);
DISPLAY 0.659574 (-40 1435);
PAINT MONO (-40 1435);
DISPLAY INVISIBLE (-40 1435);
FORCEPROP 1 LASTPIN (-50 1425) BN 12
J 0
(-62 1433);
DISPLAY 0.680851 (-62 1433);
PAINT GREEN (-62 1433);
FORCEPROP 2 LAST CDS_LIB standard
J 0
(0 1425);
PAINT MONO (0 1425);
DISPLAY INVISIBLE (0 1425);
FORCEPROP 1 LAST BODY_TYPE PLUMBING
J 0
(0 1475);
DISPLAY 0.872340 (0 1475);
PAINT GREEN (0 1475);
DISPLAY INVISIBLE (0 1475);
FORCEPROP 1 LAST HDL_TAP TRUE
J 0
(325 1300);
DISPLAY 0.872340 (325 1300);
DISPLAY INVISIBLE (325 1300);
FORCEPROP 1 LAST PATH I62
J 0
(-2 1425);
DISPLAY 0.872340 (-2 1425);
PAINT GREEN (-2 1425);
DISPLAY INVISIBLE (-2 1425);
FORCEADD TAP..1
(0 1475);
FORCEPROP 3 LASTPIN (-50 1475) SIG_NAME M_E_CPU0_SB_DQ<13>
J 0
(-40 1485);
DISPLAY 0.659574 (-40 1485);
PAINT MONO (-40 1485);
DISPLAY INVISIBLE (-40 1485);
FORCEPROP 1 LASTPIN (-50 1475) BN 13
J 0
(-62 1483);
DISPLAY 0.680851 (-62 1483);
PAINT GREEN (-62 1483);
FORCEPROP 2 LAST CDS_LIB standard
J 0
(0 1475);
PAINT MONO (0 1475);
DISPLAY INVISIBLE (0 1475);
FORCEPROP 1 LAST BODY_TYPE PLUMBING
J 0
(0 1525);
DISPLAY 0.872340 (0 1525);
PAINT GREEN (0 1525);
DISPLAY INVISIBLE (0 1525);
FORCEPROP 1 LAST HDL_TAP TRUE
J 0
(325 1350);
DISPLAY 0.872340 (325 1350);
DISPLAY INVISIBLE (325 1350);
FORCEPROP 1 LAST PATH I63
J 0
(-2 1475);
DISPLAY 0.872340 (-2 1475);
PAINT GREEN (-2 1475);
DISPLAY INVISIBLE (-2 1475);
FORCEADD TAP..1
(0 1525);
FORCEPROP 3 LASTPIN (-50 1525) SIG_NAME M_E_CPU0_SB_DQ<14>
J 0
(-40 1535);
DISPLAY 0.659574 (-40 1535);
PAINT MONO (-40 1535);
DISPLAY INVISIBLE (-40 1535);
FORCEPROP 1 LASTPIN (-50 1525) BN 14
J 0
(-62 1533);
DISPLAY 0.680851 (-62 1533);
PAINT GREEN (-62 1533);
FORCEPROP 2 LAST CDS_LIB standard
J 0
(0 1525);
PAINT MONO (0 1525);
DISPLAY INVISIBLE (0 1525);
FORCEPROP 1 LAST BODY_TYPE PLUMBING
J 0
(0 1575);
DISPLAY 0.872340 (0 1575);
PAINT GREEN (0 1575);
DISPLAY INVISIBLE (0 1575);
FORCEPROP 1 LAST HDL_TAP TRUE
J 0
(325 1400);
DISPLAY 0.872340 (325 1400);
DISPLAY INVISIBLE (325 1400);
FORCEPROP 1 LAST PATH I64
J 0
(-2 1525);
DISPLAY 0.872340 (-2 1525);
PAINT GREEN (-2 1525);
DISPLAY INVISIBLE (-2 1525);
FORCEADD TAP..1
(0 1575);
FORCEPROP 3 LASTPIN (-50 1575) SIG_NAME M_E_CPU0_SB_DQ<15>
J 0
(-40 1585);
DISPLAY 0.659574 (-40 1585);
PAINT MONO (-40 1585);
DISPLAY INVISIBLE (-40 1585);
FORCEPROP 1 LASTPIN (-50 1575) BN 15
J 0
(-62 1583);
DISPLAY 0.680851 (-62 1583);
PAINT GREEN (-62 1583);
FORCEPROP 2 LAST CDS_LIB standard
J 0
(0 1575);
PAINT MONO (0 1575);
DISPLAY INVISIBLE (0 1575);
FORCEPROP 1 LAST BODY_TYPE PLUMBING
J 0
(0 1625);
DISPLAY 0.872340 (0 1625);
PAINT GREEN (0 1625);
DISPLAY INVISIBLE (0 1625);
FORCEPROP 1 LAST HDL_TAP TRUE
J 0
(325 1450);
DISPLAY 0.872340 (325 1450);
DISPLAY INVISIBLE (325 1450);
FORCEPROP 1 LAST PATH I65
J 0
(-2 1575);
DISPLAY 0.872340 (-2 1575);
PAINT GREEN (-2 1575);
DISPLAY INVISIBLE (-2 1575);
FORCEADD TAP..1
(0 1625);
FORCEPROP 3 LASTPIN (-50 1625) SIG_NAME M_E_CPU0_SB_DQ<16>
J 0
(-40 1635);
DISPLAY 0.659574 (-40 1635);
PAINT MONO (-40 1635);
DISPLAY INVISIBLE (-40 1635);
FORCEPROP 1 LASTPIN (-50 1625) BN 16
J 0
(-62 1633);
DISPLAY 0.680851 (-62 1633);
PAINT GREEN (-62 1633);
FORCEPROP 2 LAST CDS_LIB standard
J 0
(0 1625);
PAINT MONO (0 1625);
DISPLAY INVISIBLE (0 1625);
FORCEPROP 1 LAST BODY_TYPE PLUMBING
J 0
(0 1675);
DISPLAY 0.872340 (0 1675);
PAINT GREEN (0 1675);
DISPLAY INVISIBLE (0 1675);
FORCEPROP 1 LAST HDL_TAP TRUE
J 0
(325 1500);
DISPLAY 0.872340 (325 1500);
DISPLAY INVISIBLE (325 1500);
FORCEPROP 1 LAST PATH I66
J 0
(-2 1625);
DISPLAY 0.872340 (-2 1625);
PAINT GREEN (-2 1625);
DISPLAY INVISIBLE (-2 1625);
FORCEADD TAP..1
(0 1675);
FORCEPROP 3 LASTPIN (-50 1675) SIG_NAME M_E_CPU0_SB_DQ<17>
J 0
(-40 1685);
DISPLAY 0.659574 (-40 1685);
PAINT MONO (-40 1685);
DISPLAY INVISIBLE (-40 1685);
FORCEPROP 1 LASTPIN (-50 1675) BN 17
J 0
(-62 1683);
DISPLAY 0.680851 (-62 1683);
PAINT GREEN (-62 1683);
FORCEPROP 2 LAST CDS_LIB standard
J 0
(0 1675);
PAINT MONO (0 1675);
DISPLAY INVISIBLE (0 1675);
FORCEPROP 1 LAST BODY_TYPE PLUMBING
J 0
(0 1725);
DISPLAY 0.872340 (0 1725);
PAINT GREEN (0 1725);
DISPLAY INVISIBLE (0 1725);
FORCEPROP 1 LAST HDL_TAP TRUE
J 0
(325 1550);
DISPLAY 0.872340 (325 1550);
DISPLAY INVISIBLE (325 1550);
FORCEPROP 1 LAST PATH I67
J 0
(-2 1675);
DISPLAY 0.872340 (-2 1675);
PAINT GREEN (-2 1675);
DISPLAY INVISIBLE (-2 1675);
FORCEADD TAP..1
(0 1725);
FORCEPROP 3 LASTPIN (-50 1725) SIG_NAME M_E_CPU0_SB_DQ<18>
J 0
(-40 1735);
DISPLAY 0.659574 (-40 1735);
PAINT MONO (-40 1735);
DISPLAY INVISIBLE (-40 1735);
FORCEPROP 1 LASTPIN (-50 1725) BN 18
J 0
(-62 1733);
DISPLAY 0.680851 (-62 1733);
PAINT GREEN (-62 1733);
FORCEPROP 2 LAST CDS_LIB standard
J 0
(0 1725);
PAINT MONO (0 1725);
DISPLAY INVISIBLE (0 1725);
FORCEPROP 1 LAST BODY_TYPE PLUMBING
J 0
(0 1775);
DISPLAY 0.872340 (0 1775);
PAINT GREEN (0 1775);
DISPLAY INVISIBLE (0 1775);
FORCEPROP 1 LAST HDL_TAP TRUE
J 0
(325 1600);
DISPLAY 0.872340 (325 1600);
DISPLAY INVISIBLE (325 1600);
FORCEPROP 1 LAST PATH I68
J 0
(-2 1725);
DISPLAY 0.872340 (-2 1725);
PAINT GREEN (-2 1725);
DISPLAY INVISIBLE (-2 1725);
FORCEADD TAP..1
(0 1775);
FORCEPROP 3 LASTPIN (-50 1775) SIG_NAME M_E_CPU0_SB_DQ<19>
J 0
(-40 1785);
DISPLAY 0.659574 (-40 1785);
PAINT MONO (-40 1785);
DISPLAY INVISIBLE (-40 1785);
FORCEPROP 1 LASTPIN (-50 1775) BN 19
J 0
(-62 1783);
DISPLAY 0.680851 (-62 1783);
PAINT GREEN (-62 1783);
FORCEPROP 2 LAST CDS_LIB standard
J 0
(0 1775);
PAINT MONO (0 1775);
DISPLAY INVISIBLE (0 1775);
FORCEPROP 1 LAST BODY_TYPE PLUMBING
J 0
(0 1825);
DISPLAY 0.872340 (0 1825);
PAINT GREEN (0 1825);
DISPLAY INVISIBLE (0 1825);
FORCEPROP 1 LAST HDL_TAP TRUE
J 0
(325 1650);
DISPLAY 0.872340 (325 1650);
DISPLAY INVISIBLE (325 1650);
FORCEPROP 1 LAST PATH I69
J 0
(-2 1775);
DISPLAY 0.872340 (-2 1775);
PAINT GREEN (-2 1775);
DISPLAY INVISIBLE (-2 1775);
FORCEADD OFFPAGE..1
(-2500 1475);
FORCEPROP 2 LAST $XR7 97 
J 0
(-2962 1511);
DISPLAY 0.638298 (-2962 1511);
PAINT MONO (-2962 1511);
FORCEPROP 2 LAST $XR6 96 
J 0
(-2872 1511);
DISPLAY 0.638298 (-2872 1511);
PAINT MONO (-2872 1511);
FORCEPROP 2 LAST $XR5 95 
J 0
(-2962 1439);
DISPLAY 0.638298 (-2962 1439);
PAINT MONO (-2962 1439);
FORCEPROP 2 LAST $XR4 94 
J 0
(-2872 1439);
DISPLAY 0.638298 (-2872 1439);
PAINT MONO (-2872 1439);
FORCEPROP 2 LAST $XR3 93 
J 0
(-2782 1439);
DISPLAY 0.638298 (-2782 1439);
PAINT MONO (-2782 1439);
FORCEPROP 2 LAST $XR2 92 
J 0
(-2962 1475);
DISPLAY 0.638298 (-2962 1475);
PAINT MONO (-2962 1475);
FORCEPROP 2 LAST $XR1 91 
J 0
(-2872 1475);
DISPLAY 0.638298 (-2872 1475);
PAINT MONO (-2872 1475);
FORCEPROP 2 LAST $XR0 229 
J 0
(-2782 1475);
DISPLAY 0.638298 (-2782 1475);
PAINT MONO (-2782 1475);
FORCEPROP 2 LAST CDS_LIB standard
J 0
(-2500 1475);
PAINT MONO (-2500 1475);
DISPLAY INVISIBLE (-2500 1475);
FORCEPROP 1 LAST OFFPAGE TRUE
J 0
(-2175 1350);
DISPLAY 0.872340 (-2175 1350);
DISPLAY INVISIBLE (-2175 1350);
FORCEPROP 1 LAST COMMENT_BODY TRUE
J 0
(-2375 1375);
DISPLAY 0.872340 (-2375 1375);
PAINT GREEN (-2375 1375);
DISPLAY INVISIBLE (-2375 1375);
FORCEPROP 2 LAST PATH I7
J 0
(-2450 1550);
DISPLAY 1.021277 (-2450 1550);
DISPLAY INVISIBLE (-2450 1550);
FORCEADD TAP..1
(0 1875);
FORCEPROP 3 LASTPIN (-50 1875) SIG_NAME M_E_CPU0_SB_DQ<21>
J 0
(-40 1885);
DISPLAY 0.659574 (-40 1885);
PAINT MONO (-40 1885);
DISPLAY INVISIBLE (-40 1885);
FORCEPROP 1 LASTPIN (-50 1875) BN 21
J 0
(-62 1883);
DISPLAY 0.680851 (-62 1883);
PAINT GREEN (-62 1883);
FORCEPROP 2 LAST CDS_LIB standard
J 0
(0 1875);
PAINT MONO (0 1875);
DISPLAY INVISIBLE (0 1875);
FORCEPROP 1 LAST BODY_TYPE PLUMBING
J 0
(0 1925);
DISPLAY 0.872340 (0 1925);
PAINT GREEN (0 1925);
DISPLAY INVISIBLE (0 1925);
FORCEPROP 1 LAST HDL_TAP TRUE
J 0
(325 1750);
DISPLAY 0.872340 (325 1750);
DISPLAY INVISIBLE (325 1750);
FORCEPROP 1 LAST PATH I70
J 0
(-2 1875);
DISPLAY 0.872340 (-2 1875);
PAINT GREEN (-2 1875);
DISPLAY INVISIBLE (-2 1875);
FORCEADD TAP..1
(0 1825);
FORCEPROP 3 LASTPIN (-50 1825) SIG_NAME M_E_CPU0_SB_DQ<20>
J 0
(-40 1835);
DISPLAY 0.659574 (-40 1835);
PAINT MONO (-40 1835);
DISPLAY INVISIBLE (-40 1835);
FORCEPROP 1 LASTPIN (-50 1825) BN 20
J 0
(-62 1833);
DISPLAY 0.680851 (-62 1833);
PAINT GREEN (-62 1833);
FORCEPROP 2 LAST CDS_LIB standard
J 0
(0 1825);
PAINT MONO (0 1825);
DISPLAY INVISIBLE (0 1825);
FORCEPROP 1 LAST BODY_TYPE PLUMBING
J 0
(0 1875);
DISPLAY 0.872340 (0 1875);
PAINT GREEN (0 1875);
DISPLAY INVISIBLE (0 1875);
FORCEPROP 1 LAST HDL_TAP TRUE
J 0
(325 1700);
DISPLAY 0.872340 (325 1700);
DISPLAY INVISIBLE (325 1700);
FORCEPROP 1 LAST PATH I71
J 0
(-2 1825);
DISPLAY 0.872340 (-2 1825);
PAINT GREEN (-2 1825);
DISPLAY INVISIBLE (-2 1825);
FORCEADD TAP..1
(0 1975);
FORCEPROP 3 LASTPIN (-50 1975) SIG_NAME M_E_CPU0_SB_DQ<23>
J 0
(-40 1985);
DISPLAY 0.659574 (-40 1985);
PAINT MONO (-40 1985);
DISPLAY INVISIBLE (-40 1985);
FORCEPROP 1 LASTPIN (-50 1975) BN 23
J 0
(-62 1983);
DISPLAY 0.680851 (-62 1983);
PAINT GREEN (-62 1983);
FORCEPROP 2 LAST CDS_LIB standard
J 0
(0 1975);
DISPLAY INVISIBLE (0 1975);
FORCEPROP 1 LAST BODY_TYPE PLUMBING
J 0
(0 2025);
DISPLAY 0.872340 (0 2025);
PAINT GREEN (0 2025);
DISPLAY INVISIBLE (0 2025);
FORCEPROP 1 LAST HDL_TAP TRUE
J 0
(325 1850);
DISPLAY 0.872340 (325 1850);
DISPLAY INVISIBLE (325 1850);
FORCEPROP 1 LAST PATH I72
J 0
(-2 1975);
DISPLAY 0.872340 (-2 1975);
PAINT GREEN (-2 1975);
DISPLAY INVISIBLE (-2 1975);
FORCEADD TAP..1
(0 2025);
FORCEPROP 3 LASTPIN (-50 2025) SIG_NAME M_E_CPU0_SB_DQ<24>
J 0
(-40 2035);
DISPLAY 0.659574 (-40 2035);
PAINT MONO (-40 2035);
DISPLAY INVISIBLE (-40 2035);
FORCEPROP 1 LASTPIN (-50 2025) BN 24
J 0
(-62 2033);
DISPLAY 0.680851 (-62 2033);
PAINT GREEN (-62 2033);
FORCEPROP 2 LAST CDS_LIB standard
J 0
(0 2025);
DISPLAY INVISIBLE (0 2025);
FORCEPROP 1 LAST BODY_TYPE PLUMBING
J 0
(0 2075);
DISPLAY 0.872340 (0 2075);
PAINT GREEN (0 2075);
DISPLAY INVISIBLE (0 2075);
FORCEPROP 1 LAST HDL_TAP TRUE
J 0
(325 1900);
DISPLAY 0.872340 (325 1900);
DISPLAY INVISIBLE (325 1900);
FORCEPROP 1 LAST PATH I73
J 0
(-2 2025);
DISPLAY 0.872340 (-2 2025);
PAINT GREEN (-2 2025);
DISPLAY INVISIBLE (-2 2025);
FORCEADD TAP..1
(0 1925);
FORCEPROP 3 LASTPIN (-50 1925) SIG_NAME M_E_CPU0_SB_DQ<22>
J 0
(-40 1935);
DISPLAY 0.659574 (-40 1935);
PAINT MONO (-40 1935);
DISPLAY INVISIBLE (-40 1935);
FORCEPROP 1 LASTPIN (-50 1925) BN 22
J 0
(-62 1933);
DISPLAY 0.680851 (-62 1933);
PAINT GREEN (-62 1933);
FORCEPROP 2 LAST CDS_LIB standard
J 0
(0 1925);
DISPLAY INVISIBLE (0 1925);
FORCEPROP 1 LAST BODY_TYPE PLUMBING
J 0
(0 1975);
DISPLAY 0.872340 (0 1975);
PAINT GREEN (0 1975);
DISPLAY INVISIBLE (0 1975);
FORCEPROP 1 LAST HDL_TAP TRUE
J 0
(325 1800);
DISPLAY 0.872340 (325 1800);
DISPLAY INVISIBLE (325 1800);
FORCEPROP 1 LAST PATH I74
J 0
(-2 1925);
DISPLAY 0.872340 (-2 1925);
PAINT GREEN (-2 1925);
DISPLAY INVISIBLE (-2 1925);
FORCEADD TAP..1
(0 2075);
FORCEPROP 3 LASTPIN (-50 2075) SIG_NAME M_E_CPU0_SB_DQ<25>
J 0
(-40 2085);
DISPLAY 0.659574 (-40 2085);
PAINT MONO (-40 2085);
DISPLAY INVISIBLE (-40 2085);
FORCEPROP 1 LASTPIN (-50 2075) BN 25
J 0
(-62 2083);
DISPLAY 0.680851 (-62 2083);
PAINT GREEN (-62 2083);
FORCEPROP 2 LAST CDS_LIB standard
J 0
(0 2075);
DISPLAY INVISIBLE (0 2075);
FORCEPROP 1 LAST BODY_TYPE PLUMBING
J 0
(0 2125);
DISPLAY 0.872340 (0 2125);
PAINT GREEN (0 2125);
DISPLAY INVISIBLE (0 2125);
FORCEPROP 1 LAST HDL_TAP TRUE
J 0
(325 1950);
DISPLAY 0.872340 (325 1950);
DISPLAY INVISIBLE (325 1950);
FORCEPROP 1 LAST PATH I75
J 0
(-2 2075);
DISPLAY 0.872340 (-2 2075);
PAINT GREEN (-2 2075);
DISPLAY INVISIBLE (-2 2075);
FORCEADD TAP..1
(0 2125);
FORCEPROP 3 LASTPIN (-50 2125) SIG_NAME M_E_CPU0_SB_DQ<26>
J 0
(-40 2135);
DISPLAY 0.659574 (-40 2135);
PAINT MONO (-40 2135);
DISPLAY INVISIBLE (-40 2135);
FORCEPROP 1 LASTPIN (-50 2125) BN 26
J 0
(-62 2133);
DISPLAY 0.680851 (-62 2133);
PAINT GREEN (-62 2133);
FORCEPROP 2 LAST CDS_LIB standard
J 0
(0 2125);
DISPLAY INVISIBLE (0 2125);
FORCEPROP 1 LAST BODY_TYPE PLUMBING
J 0
(0 2175);
DISPLAY 0.872340 (0 2175);
PAINT GREEN (0 2175);
DISPLAY INVISIBLE (0 2175);
FORCEPROP 1 LAST HDL_TAP TRUE
J 0
(325 2000);
DISPLAY 0.872340 (325 2000);
DISPLAY INVISIBLE (325 2000);
FORCEPROP 1 LAST PATH I76
J 0
(-2 2125);
DISPLAY 0.872340 (-2 2125);
PAINT GREEN (-2 2125);
DISPLAY INVISIBLE (-2 2125);
FORCEADD TAP..1
(0 2175);
FORCEPROP 3 LASTPIN (-50 2175) SIG_NAME M_E_CPU0_SB_DQ<27>
J 0
(-40 2185);
DISPLAY 0.659574 (-40 2185);
PAINT MONO (-40 2185);
DISPLAY INVISIBLE (-40 2185);
FORCEPROP 1 LASTPIN (-50 2175) BN 27
J 0
(-62 2183);
DISPLAY 0.680851 (-62 2183);
PAINT GREEN (-62 2183);
FORCEPROP 2 LAST CDS_LIB standard
J 0
(0 2175);
DISPLAY INVISIBLE (0 2175);
FORCEPROP 1 LAST BODY_TYPE PLUMBING
J 0
(0 2225);
DISPLAY 0.872340 (0 2225);
PAINT GREEN (0 2225);
DISPLAY INVISIBLE (0 2225);
FORCEPROP 1 LAST HDL_TAP TRUE
J 0
(325 2050);
DISPLAY 0.872340 (325 2050);
DISPLAY INVISIBLE (325 2050);
FORCEPROP 1 LAST PATH I77
J 0
(-2 2175);
DISPLAY 0.872340 (-2 2175);
PAINT GREEN (-2 2175);
DISPLAY INVISIBLE (-2 2175);
FORCEADD TAP..1
(0 2225);
FORCEPROP 3 LASTPIN (-50 2225) SIG_NAME M_E_CPU0_SB_DQ<28>
J 0
(-40 2235);
DISPLAY 0.659574 (-40 2235);
PAINT MONO (-40 2235);
DISPLAY INVISIBLE (-40 2235);
FORCEPROP 1 LASTPIN (-50 2225) BN 28
J 0
(-62 2233);
DISPLAY 0.680851 (-62 2233);
PAINT GREEN (-62 2233);
FORCEPROP 2 LAST CDS_LIB standard
J 0
(0 2225);
DISPLAY INVISIBLE (0 2225);
FORCEPROP 1 LAST BODY_TYPE PLUMBING
J 0
(0 2275);
DISPLAY 0.872340 (0 2275);
PAINT GREEN (0 2275);
DISPLAY INVISIBLE (0 2275);
FORCEPROP 1 LAST HDL_TAP TRUE
J 0
(325 2100);
DISPLAY 0.872340 (325 2100);
DISPLAY INVISIBLE (325 2100);
FORCEPROP 1 LAST PATH I78
J 0
(-2 2225);
DISPLAY 0.872340 (-2 2225);
PAINT GREEN (-2 2225);
DISPLAY INVISIBLE (-2 2225);
FORCEADD TAP..1
(0 2275);
FORCEPROP 3 LASTPIN (-50 2275) SIG_NAME M_E_CPU0_SB_DQ<29>
J 0
(-40 2285);
DISPLAY 0.659574 (-40 2285);
PAINT MONO (-40 2285);
DISPLAY INVISIBLE (-40 2285);
FORCEPROP 1 LASTPIN (-50 2275) BN 29
J 0
(-62 2283);
DISPLAY 0.680851 (-62 2283);
PAINT GREEN (-62 2283);
FORCEPROP 2 LAST CDS_LIB standard
J 0
(0 2275);
DISPLAY INVISIBLE (0 2275);
FORCEPROP 1 LAST BODY_TYPE PLUMBING
J 0
(0 2325);
DISPLAY 0.872340 (0 2325);
PAINT GREEN (0 2325);
DISPLAY INVISIBLE (0 2325);
FORCEPROP 1 LAST HDL_TAP TRUE
J 0
(325 2150);
DISPLAY 0.872340 (325 2150);
DISPLAY INVISIBLE (325 2150);
FORCEPROP 1 LAST PATH I79
J 0
(-2 2275);
DISPLAY 0.872340 (-2 2275);
PAINT GREEN (-2 2275);
DISPLAY INVISIBLE (-2 2275);
FORCEADD OFFPAGE..1
(-2500 1525);
FORCEPROP 2 LAST $XR0 90 
J 0
(-2751 1525);
DISPLAY 0.638298 (-2751 1525);
PAINT MONO (-2751 1525);
FORCEPROP 2 LAST CDS_LIB standard
J 0
(-2500 1525);
PAINT MONO (-2500 1525);
DISPLAY INVISIBLE (-2500 1525);
FORCEPROP 1 LAST OFFPAGE TRUE
J 0
(-2175 1400);
DISPLAY 0.872340 (-2175 1400);
DISPLAY INVISIBLE (-2175 1400);
FORCEPROP 1 LAST COMMENT_BODY TRUE
J 0
(-2375 1425);
DISPLAY 0.872340 (-2375 1425);
PAINT GREEN (-2375 1425);
DISPLAY INVISIBLE (-2375 1425);
FORCEPROP 2 LAST PATH I8
J 0
(-2450 1600);
DISPLAY 1.021277 (-2450 1600);
DISPLAY INVISIBLE (-2450 1600);
FORCEADD TAP..1
(0 2375);
FORCEPROP 3 LASTPIN (-50 2375) SIG_NAME M_E_CPU0_SB_DQ<31>
J 0
(-40 2385);
DISPLAY 0.659574 (-40 2385);
PAINT MONO (-40 2385);
DISPLAY INVISIBLE (-40 2385);
FORCEPROP 1 LASTPIN (-50 2375) BN 31
J 0
(-62 2383);
DISPLAY 0.680851 (-62 2383);
PAINT GREEN (-62 2383);
FORCEPROP 2 LAST CDS_LIB standard
J 0
(0 2375);
DISPLAY INVISIBLE (0 2375);
FORCEPROP 1 LAST BODY_TYPE PLUMBING
J 0
(0 2425);
DISPLAY 0.872340 (0 2425);
PAINT GREEN (0 2425);
DISPLAY INVISIBLE (0 2425);
FORCEPROP 1 LAST HDL_TAP TRUE
J 0
(325 2250);
DISPLAY 0.872340 (325 2250);
DISPLAY INVISIBLE (325 2250);
FORCEPROP 1 LAST PATH I80
J 0
(-2 2375);
DISPLAY 0.872340 (-2 2375);
PAINT GREEN (-2 2375);
DISPLAY INVISIBLE (-2 2375);
FORCEADD TAP..1
(0 2325);
FORCEPROP 3 LASTPIN (-50 2325) SIG_NAME M_E_CPU0_SB_DQ<30>
J 0
(-40 2335);
DISPLAY 0.659574 (-40 2335);
PAINT MONO (-40 2335);
DISPLAY INVISIBLE (-40 2335);
FORCEPROP 1 LASTPIN (-50 2325) BN 30
J 0
(-62 2333);
DISPLAY 0.680851 (-62 2333);
PAINT GREEN (-62 2333);
FORCEPROP 2 LAST CDS_LIB standard
J 0
(0 2325);
DISPLAY INVISIBLE (0 2325);
FORCEPROP 1 LAST BODY_TYPE PLUMBING
J 0
(0 2375);
DISPLAY 0.872340 (0 2375);
PAINT GREEN (0 2375);
DISPLAY INVISIBLE (0 2375);
FORCEPROP 1 LAST HDL_TAP TRUE
J 0
(325 2200);
DISPLAY 0.872340 (325 2200);
DISPLAY INVISIBLE (325 2200);
FORCEPROP 1 LAST PATH I81
J 0
(-2 2325);
DISPLAY 0.872340 (-2 2325);
PAINT GREEN (-2 2325);
DISPLAY INVISIBLE (-2 2325);
FORCEADD TAP..1
(0 2475);
FORCEPROP 3 LASTPIN (-50 2475) SIG_NAME M_E_CPU0_SA_DQ<0>
J 0
(-40 2485);
DISPLAY 0.659574 (-40 2485);
PAINT MONO (-40 2485);
DISPLAY INVISIBLE (-40 2485);
FORCEPROP 1 LASTPIN (-50 2475) BN 0
J 0
(-62 2483);
DISPLAY 0.680851 (-62 2483);
PAINT GREEN (-62 2483);
FORCEPROP 2 LAST CDS_LIB standard
J 0
(0 2475);
PAINT MONO (0 2475);
DISPLAY INVISIBLE (0 2475);
FORCEPROP 1 LAST BODY_TYPE PLUMBING
J 0
(0 2525);
DISPLAY 0.872340 (0 2525);
PAINT GREEN (0 2525);
DISPLAY INVISIBLE (0 2525);
FORCEPROP 1 LAST HDL_TAP TRUE
J 0
(325 2350);
DISPLAY 0.872340 (325 2350);
DISPLAY INVISIBLE (325 2350);
FORCEPROP 1 LAST PATH I82
J 0
(-2 2475);
DISPLAY 0.872340 (-2 2475);
PAINT GREEN (-2 2475);
DISPLAY INVISIBLE (-2 2475);
FORCEADD TAP..1
(0 2525);
FORCEPROP 3 LASTPIN (-50 2525) SIG_NAME M_E_CPU0_SA_DQ<1>
J 0
(-40 2535);
DISPLAY 0.659574 (-40 2535);
PAINT MONO (-40 2535);
DISPLAY INVISIBLE (-40 2535);
FORCEPROP 1 LASTPIN (-50 2525) BN 1
J 0
(-62 2533);
DISPLAY 0.680851 (-62 2533);
PAINT GREEN (-62 2533);
FORCEPROP 2 LAST CDS_LIB standard
J 0
(0 2525);
PAINT MONO (0 2525);
DISPLAY INVISIBLE (0 2525);
FORCEPROP 1 LAST BODY_TYPE PLUMBING
J 0
(0 2575);
DISPLAY 0.872340 (0 2575);
PAINT GREEN (0 2575);
DISPLAY INVISIBLE (0 2575);
FORCEPROP 1 LAST HDL_TAP TRUE
J 0
(325 2400);
DISPLAY 0.872340 (325 2400);
DISPLAY INVISIBLE (325 2400);
FORCEPROP 1 LAST PATH I83
J 0
(-2 2525);
DISPLAY 0.872340 (-2 2525);
PAINT GREEN (-2 2525);
DISPLAY INVISIBLE (-2 2525);
FORCEADD TAP..1
(0 2575);
FORCEPROP 3 LASTPIN (-50 2575) SIG_NAME M_E_CPU0_SA_DQ<2>
J 0
(-40 2585);
DISPLAY 0.659574 (-40 2585);
PAINT MONO (-40 2585);
DISPLAY INVISIBLE (-40 2585);
FORCEPROP 1 LASTPIN (-50 2575) BN 2
J 0
(-62 2583);
DISPLAY 0.680851 (-62 2583);
PAINT GREEN (-62 2583);
FORCEPROP 2 LAST CDS_LIB standard
J 0
(0 2575);
PAINT MONO (0 2575);
DISPLAY INVISIBLE (0 2575);
FORCEPROP 1 LAST BODY_TYPE PLUMBING
J 0
(0 2625);
DISPLAY 0.872340 (0 2625);
PAINT GREEN (0 2625);
DISPLAY INVISIBLE (0 2625);
FORCEPROP 1 LAST HDL_TAP TRUE
J 0
(325 2450);
DISPLAY 0.872340 (325 2450);
DISPLAY INVISIBLE (325 2450);
FORCEPROP 1 LAST PATH I84
J 0
(-2 2575);
DISPLAY 0.872340 (-2 2575);
PAINT GREEN (-2 2575);
DISPLAY INVISIBLE (-2 2575);
FORCEADD TAP..1
(0 2625);
FORCEPROP 3 LASTPIN (-50 2625) SIG_NAME M_E_CPU0_SA_DQ<3>
J 0
(-40 2635);
DISPLAY 0.659574 (-40 2635);
PAINT MONO (-40 2635);
DISPLAY INVISIBLE (-40 2635);
FORCEPROP 1 LASTPIN (-50 2625) BN 3
J 0
(-62 2633);
DISPLAY 0.680851 (-62 2633);
PAINT GREEN (-62 2633);
FORCEPROP 2 LAST CDS_LIB standard
J 0
(0 2625);
PAINT MONO (0 2625);
DISPLAY INVISIBLE (0 2625);
FORCEPROP 1 LAST BODY_TYPE PLUMBING
J 0
(0 2675);
DISPLAY 0.872340 (0 2675);
PAINT GREEN (0 2675);
DISPLAY INVISIBLE (0 2675);
FORCEPROP 1 LAST HDL_TAP TRUE
J 0
(325 2500);
DISPLAY 0.872340 (325 2500);
DISPLAY INVISIBLE (325 2500);
FORCEPROP 1 LAST PATH I85
J 0
(-2 2625);
DISPLAY 0.872340 (-2 2625);
PAINT GREEN (-2 2625);
DISPLAY INVISIBLE (-2 2625);
FORCEADD TAP..1
(0 2675);
FORCEPROP 3 LASTPIN (-50 2675) SIG_NAME M_E_CPU0_SA_DQ<4>
J 0
(-40 2685);
DISPLAY 0.659574 (-40 2685);
PAINT MONO (-40 2685);
DISPLAY INVISIBLE (-40 2685);
FORCEPROP 1 LASTPIN (-50 2675) BN 4
J 0
(-62 2683);
DISPLAY 0.680851 (-62 2683);
PAINT GREEN (-62 2683);
FORCEPROP 2 LAST CDS_LIB standard
J 0
(0 2675);
PAINT MONO (0 2675);
DISPLAY INVISIBLE (0 2675);
FORCEPROP 1 LAST BODY_TYPE PLUMBING
J 0
(0 2725);
DISPLAY 0.872340 (0 2725);
PAINT GREEN (0 2725);
DISPLAY INVISIBLE (0 2725);
FORCEPROP 1 LAST HDL_TAP TRUE
J 0
(325 2550);
DISPLAY 0.872340 (325 2550);
DISPLAY INVISIBLE (325 2550);
FORCEPROP 1 LAST PATH I86
J 0
(-2 2675);
DISPLAY 0.872340 (-2 2675);
PAINT GREEN (-2 2675);
DISPLAY INVISIBLE (-2 2675);
FORCEADD TAP..1
(0 2725);
FORCEPROP 3 LASTPIN (-50 2725) SIG_NAME M_E_CPU0_SA_DQ<5>
J 0
(-40 2735);
DISPLAY 0.659574 (-40 2735);
PAINT MONO (-40 2735);
DISPLAY INVISIBLE (-40 2735);
FORCEPROP 1 LASTPIN (-50 2725) BN 5
J 0
(-62 2733);
DISPLAY 0.680851 (-62 2733);
PAINT GREEN (-62 2733);
FORCEPROP 2 LAST CDS_LIB standard
J 0
(0 2725);
PAINT MONO (0 2725);
DISPLAY INVISIBLE (0 2725);
FORCEPROP 1 LAST BODY_TYPE PLUMBING
J 0
(0 2775);
DISPLAY 0.872340 (0 2775);
PAINT GREEN (0 2775);
DISPLAY INVISIBLE (0 2775);
FORCEPROP 1 LAST HDL_TAP TRUE
J 0
(325 2600);
DISPLAY 0.872340 (325 2600);
DISPLAY INVISIBLE (325 2600);
FORCEPROP 1 LAST PATH I87
J 0
(-2 2725);
DISPLAY 0.872340 (-2 2725);
PAINT GREEN (-2 2725);
DISPLAY INVISIBLE (-2 2725);
FORCEADD TAP..1
(0 2775);
FORCEPROP 3 LASTPIN (-50 2775) SIG_NAME M_E_CPU0_SA_DQ<6>
J 0
(-40 2785);
DISPLAY 0.659574 (-40 2785);
PAINT MONO (-40 2785);
DISPLAY INVISIBLE (-40 2785);
FORCEPROP 1 LASTPIN (-50 2775) BN 6
J 0
(-62 2783);
DISPLAY 0.680851 (-62 2783);
PAINT GREEN (-62 2783);
FORCEPROP 2 LAST CDS_LIB standard
J 0
(0 2775);
PAINT MONO (0 2775);
DISPLAY INVISIBLE (0 2775);
FORCEPROP 1 LAST BODY_TYPE PLUMBING
J 0
(0 2825);
DISPLAY 0.872340 (0 2825);
PAINT GREEN (0 2825);
DISPLAY INVISIBLE (0 2825);
FORCEPROP 1 LAST HDL_TAP TRUE
J 0
(325 2650);
DISPLAY 0.872340 (325 2650);
DISPLAY INVISIBLE (325 2650);
FORCEPROP 1 LAST PATH I88
J 0
(-2 2775);
DISPLAY 0.872340 (-2 2775);
PAINT GREEN (-2 2775);
DISPLAY INVISIBLE (-2 2775);
FORCEADD TAP..1
(0 2875);
FORCEPROP 3 LASTPIN (-50 2875) SIG_NAME M_E_CPU0_SA_DQ<8>
J 0
(-40 2885);
DISPLAY 0.659574 (-40 2885);
PAINT MONO (-40 2885);
DISPLAY INVISIBLE (-40 2885);
FORCEPROP 1 LASTPIN (-50 2875) BN 8
J 0
(-62 2883);
DISPLAY 0.680851 (-62 2883);
PAINT GREEN (-62 2883);
FORCEPROP 2 LAST CDS_LIB standard
J 0
(0 2875);
PAINT MONO (0 2875);
DISPLAY INVISIBLE (0 2875);
FORCEPROP 1 LAST BODY_TYPE PLUMBING
J 0
(0 2925);
DISPLAY 0.872340 (0 2925);
PAINT GREEN (0 2925);
DISPLAY INVISIBLE (0 2925);
FORCEPROP 1 LAST HDL_TAP TRUE
J 0
(325 2750);
DISPLAY 0.872340 (325 2750);
DISPLAY INVISIBLE (325 2750);
FORCEPROP 1 LAST PATH I89
J 0
(-2 2875);
DISPLAY 0.872340 (-2 2875);
PAINT GREEN (-2 2875);
DISPLAY INVISIBLE (-2 2875);
FORCEADD OFFPAGE..1
(-2575 1775);
FORCEPROP 2 LAST $XR3 93 
J 0
(-2827 1739);
DISPLAY 0.638298 (-2827 1739);
PAINT MONO (-2827 1739);
FORCEPROP 2 LAST $XR2 92 
J 0
(-3007 1775);
DISPLAY 0.638298 (-3007 1775);
PAINT MONO (-3007 1775);
FORCEPROP 2 LAST $XR1 91 
J 0
(-2917 1775);
DISPLAY 0.638298 (-2917 1775);
PAINT MONO (-2917 1775);
FORCEPROP 2 LAST $XR0 129 
J 0
(-2827 1775);
DISPLAY 0.638298 (-2827 1775);
PAINT MONO (-2827 1775);
FORCEPROP 2 LAST CDS_LIB standard
J 0
(-2575 1775);
PAINT MONO (-2575 1775);
DISPLAY INVISIBLE (-2575 1775);
FORCEPROP 1 LAST OFFPAGE TRUE
J 0
(-2250 1650);
DISPLAY 0.872340 (-2250 1650);
DISPLAY INVISIBLE (-2250 1650);
FORCEPROP 1 LAST COMMENT_BODY TRUE
J 0
(-2450 1675);
DISPLAY 0.872340 (-2450 1675);
PAINT GREEN (-2450 1675);
DISPLAY INVISIBLE (-2450 1675);
FORCEPROP 2 LAST PATH I9
J 0
(-2525 1850);
DISPLAY 1.021277 (-2525 1850);
DISPLAY INVISIBLE (-2525 1850);
FORCEADD TAP..1
(0 2825);
FORCEPROP 3 LASTPIN (-50 2825) SIG_NAME M_E_CPU0_SA_DQ<7>
J 0
(-40 2835);
DISPLAY 0.659574 (-40 2835);
PAINT MONO (-40 2835);
DISPLAY INVISIBLE (-40 2835);
FORCEPROP 1 LASTPIN (-50 2825) BN 7
J 0
(-62 2833);
DISPLAY 0.680851 (-62 2833);
PAINT GREEN (-62 2833);
FORCEPROP 2 LAST CDS_LIB standard
J 0
(0 2825);
PAINT MONO (0 2825);
DISPLAY INVISIBLE (0 2825);
FORCEPROP 1 LAST BODY_TYPE PLUMBING
J 0
(0 2875);
DISPLAY 0.872340 (0 2875);
PAINT GREEN (0 2875);
DISPLAY INVISIBLE (0 2875);
FORCEPROP 1 LAST HDL_TAP TRUE
J 0
(325 2700);
DISPLAY 0.872340 (325 2700);
DISPLAY INVISIBLE (325 2700);
FORCEPROP 1 LAST PATH I90
J 0
(-2 2825);
DISPLAY 0.872340 (-2 2825);
PAINT GREEN (-2 2825);
DISPLAY INVISIBLE (-2 2825);
FORCEADD TAP..1
(0 2925);
FORCEPROP 3 LASTPIN (-50 2925) SIG_NAME M_E_CPU0_SA_DQ<9>
J 0
(-40 2935);
DISPLAY 0.659574 (-40 2935);
PAINT MONO (-40 2935);
DISPLAY INVISIBLE (-40 2935);
FORCEPROP 1 LASTPIN (-50 2925) BN 9
J 0
(-62 2933);
DISPLAY 0.680851 (-62 2933);
PAINT GREEN (-62 2933);
FORCEPROP 2 LAST CDS_LIB standard
J 0
(0 2925);
PAINT MONO (0 2925);
DISPLAY INVISIBLE (0 2925);
FORCEPROP 1 LAST BODY_TYPE PLUMBING
J 0
(0 2975);
DISPLAY 0.872340 (0 2975);
PAINT GREEN (0 2975);
DISPLAY INVISIBLE (0 2975);
FORCEPROP 1 LAST HDL_TAP TRUE
J 0
(325 2800);
DISPLAY 0.872340 (325 2800);
DISPLAY INVISIBLE (325 2800);
FORCEPROP 1 LAST PATH I91
J 0
(-2 2925);
DISPLAY 0.872340 (-2 2925);
PAINT GREEN (-2 2925);
DISPLAY INVISIBLE (-2 2925);
FORCEADD TAP..1
(0 3025);
FORCEPROP 3 LASTPIN (-50 3025) SIG_NAME M_E_CPU0_SA_DQ<11>
J 0
(-40 3035);
DISPLAY 0.659574 (-40 3035);
PAINT MONO (-40 3035);
DISPLAY INVISIBLE (-40 3035);
FORCEPROP 1 LASTPIN (-50 3025) BN 11
J 0
(-62 3033);
DISPLAY 0.680851 (-62 3033);
PAINT GREEN (-62 3033);
FORCEPROP 2 LAST CDS_LIB standard
J 0
(0 3025);
PAINT MONO (0 3025);
DISPLAY INVISIBLE (0 3025);
FORCEPROP 1 LAST BODY_TYPE PLUMBING
J 0
(0 3075);
DISPLAY 0.872340 (0 3075);
PAINT GREEN (0 3075);
DISPLAY INVISIBLE (0 3075);
FORCEPROP 1 LAST HDL_TAP TRUE
J 0
(325 2900);
DISPLAY 0.872340 (325 2900);
DISPLAY INVISIBLE (325 2900);
FORCEPROP 1 LAST PATH I92
J 0
(-2 3025);
DISPLAY 0.872340 (-2 3025);
PAINT GREEN (-2 3025);
DISPLAY INVISIBLE (-2 3025);
FORCEADD TAP..1
(0 2975);
FORCEPROP 3 LASTPIN (-50 2975) SIG_NAME M_E_CPU0_SA_DQ<10>
J 0
(-40 2985);
DISPLAY 0.659574 (-40 2985);
PAINT MONO (-40 2985);
DISPLAY INVISIBLE (-40 2985);
FORCEPROP 1 LASTPIN (-50 2975) BN 10
J 0
(-62 2983);
DISPLAY 0.680851 (-62 2983);
PAINT GREEN (-62 2983);
FORCEPROP 2 LAST CDS_LIB standard
J 0
(0 2975);
PAINT MONO (0 2975);
DISPLAY INVISIBLE (0 2975);
FORCEPROP 1 LAST BODY_TYPE PLUMBING
J 0
(0 3025);
DISPLAY 0.872340 (0 3025);
PAINT GREEN (0 3025);
DISPLAY INVISIBLE (0 3025);
FORCEPROP 1 LAST HDL_TAP TRUE
J 0
(325 2850);
DISPLAY 0.872340 (325 2850);
DISPLAY INVISIBLE (325 2850);
FORCEPROP 1 LAST PATH I93
J 0
(-2 2975);
DISPLAY 0.872340 (-2 2975);
PAINT GREEN (-2 2975);
DISPLAY INVISIBLE (-2 2975);
FORCEADD TAP..1
(0 3125);
FORCEPROP 3 LASTPIN (-50 3125) SIG_NAME M_E_CPU0_SA_DQ<13>
J 0
(-40 3135);
DISPLAY 0.659574 (-40 3135);
PAINT MONO (-40 3135);
DISPLAY INVISIBLE (-40 3135);
FORCEPROP 1 LASTPIN (-50 3125) BN 13
J 0
(-62 3133);
DISPLAY 0.680851 (-62 3133);
PAINT GREEN (-62 3133);
FORCEPROP 2 LAST CDS_LIB standard
J 0
(0 3125);
PAINT MONO (0 3125);
DISPLAY INVISIBLE (0 3125);
FORCEPROP 1 LAST BODY_TYPE PLUMBING
J 0
(0 3175);
DISPLAY 0.872340 (0 3175);
PAINT GREEN (0 3175);
DISPLAY INVISIBLE (0 3175);
FORCEPROP 1 LAST HDL_TAP TRUE
J 0
(325 3000);
DISPLAY 0.872340 (325 3000);
DISPLAY INVISIBLE (325 3000);
FORCEPROP 1 LAST PATH I94
J 0
(-2 3125);
DISPLAY 0.872340 (-2 3125);
PAINT GREEN (-2 3125);
DISPLAY INVISIBLE (-2 3125);
FORCEADD TAP..1
(0 3175);
FORCEPROP 3 LASTPIN (-50 3175) SIG_NAME M_E_CPU0_SA_DQ<14>
J 0
(-40 3185);
DISPLAY 0.659574 (-40 3185);
PAINT MONO (-40 3185);
DISPLAY INVISIBLE (-40 3185);
FORCEPROP 1 LASTPIN (-50 3175) BN 14
J 0
(-62 3183);
DISPLAY 0.680851 (-62 3183);
PAINT GREEN (-62 3183);
FORCEPROP 2 LAST CDS_LIB standard
J 0
(0 3175);
PAINT MONO (0 3175);
DISPLAY INVISIBLE (0 3175);
FORCEPROP 1 LAST BODY_TYPE PLUMBING
J 0
(0 3225);
DISPLAY 0.872340 (0 3225);
PAINT GREEN (0 3225);
DISPLAY INVISIBLE (0 3225);
FORCEPROP 1 LAST HDL_TAP TRUE
J 0
(325 3050);
DISPLAY 0.872340 (325 3050);
DISPLAY INVISIBLE (325 3050);
FORCEPROP 1 LAST PATH I95
J 0
(-2 3175);
DISPLAY 0.872340 (-2 3175);
PAINT GREEN (-2 3175);
DISPLAY INVISIBLE (-2 3175);
FORCEADD TAP..1
(0 3075);
FORCEPROP 3 LASTPIN (-50 3075) SIG_NAME M_E_CPU0_SA_DQ<12>
J 0
(-40 3085);
DISPLAY 0.659574 (-40 3085);
PAINT MONO (-40 3085);
DISPLAY INVISIBLE (-40 3085);
FORCEPROP 1 LASTPIN (-50 3075) BN 12
J 0
(-62 3083);
DISPLAY 0.680851 (-62 3083);
PAINT GREEN (-62 3083);
FORCEPROP 2 LAST CDS_LIB standard
J 0
(0 3075);
PAINT MONO (0 3075);
DISPLAY INVISIBLE (0 3075);
FORCEPROP 1 LAST BODY_TYPE PLUMBING
J 0
(0 3125);
DISPLAY 0.872340 (0 3125);
PAINT GREEN (0 3125);
DISPLAY INVISIBLE (0 3125);
FORCEPROP 1 LAST HDL_TAP TRUE
J 0
(325 2950);
DISPLAY 0.872340 (325 2950);
DISPLAY INVISIBLE (325 2950);
FORCEPROP 1 LAST PATH I96
J 0
(-2 3075);
DISPLAY 0.872340 (-2 3075);
PAINT GREEN (-2 3075);
DISPLAY INVISIBLE (-2 3075);
FORCEADD TAP..1
(0 3275);
FORCEPROP 3 LASTPIN (-50 3275) SIG_NAME M_E_CPU0_SA_DQ<16>
J 0
(-40 3285);
DISPLAY 0.659574 (-40 3285);
PAINT MONO (-40 3285);
DISPLAY INVISIBLE (-40 3285);
FORCEPROP 1 LASTPIN (-50 3275) BN 16
J 0
(-62 3283);
DISPLAY 0.680851 (-62 3283);
PAINT GREEN (-62 3283);
FORCEPROP 2 LAST CDS_LIB standard
J 0
(0 3275);
PAINT MONO (0 3275);
DISPLAY INVISIBLE (0 3275);
FORCEPROP 1 LAST BODY_TYPE PLUMBING
J 0
(0 3325);
DISPLAY 0.872340 (0 3325);
PAINT GREEN (0 3325);
DISPLAY INVISIBLE (0 3325);
FORCEPROP 1 LAST HDL_TAP TRUE
J 0
(325 3150);
DISPLAY 0.872340 (325 3150);
DISPLAY INVISIBLE (325 3150);
FORCEPROP 1 LAST PATH I97
J 0
(-2 3275);
DISPLAY 0.872340 (-2 3275);
PAINT GREEN (-2 3275);
DISPLAY INVISIBLE (-2 3275);
FORCEADD TAP..1
(0 3225);
FORCEPROP 3 LASTPIN (-50 3225) SIG_NAME M_E_CPU0_SA_DQ<15>
J 0
(-40 3235);
DISPLAY 0.659574 (-40 3235);
PAINT MONO (-40 3235);
DISPLAY INVISIBLE (-40 3235);
FORCEPROP 1 LASTPIN (-50 3225) BN 15
J 0
(-62 3233);
DISPLAY 0.680851 (-62 3233);
PAINT GREEN (-62 3233);
FORCEPROP 2 LAST CDS_LIB standard
J 0
(0 3225);
PAINT MONO (0 3225);
DISPLAY INVISIBLE (0 3225);
FORCEPROP 1 LAST BODY_TYPE PLUMBING
J 0
(0 3275);
DISPLAY 0.872340 (0 3275);
PAINT GREEN (0 3275);
DISPLAY INVISIBLE (0 3275);
FORCEPROP 1 LAST HDL_TAP TRUE
J 0
(325 3100);
DISPLAY 0.872340 (325 3100);
DISPLAY INVISIBLE (325 3100);
FORCEPROP 1 LAST PATH I98
J 0
(-2 3225);
DISPLAY 0.872340 (-2 3225);
PAINT GREEN (-2 3225);
DISPLAY INVISIBLE (-2 3225);
FORCEADD TAP..1
(0 3425);
FORCEPROP 3 LASTPIN (-50 3425) SIG_NAME M_E_CPU0_SA_DQ<19>
J 0
(-40 3435);
DISPLAY 0.659574 (-40 3435);
PAINT MONO (-40 3435);
DISPLAY INVISIBLE (-40 3435);
FORCEPROP 1 LASTPIN (-50 3425) BN 19
J 0
(-62 3433);
DISPLAY 0.680851 (-62 3433);
PAINT GREEN (-62 3433);
FORCEPROP 2 LAST CDS_LIB standard
J 0
(0 3425);
PAINT MONO (0 3425);
DISPLAY INVISIBLE (0 3425);
FORCEPROP 1 LAST BODY_TYPE PLUMBING
J 0
(0 3475);
DISPLAY 0.872340 (0 3475);
PAINT GREEN (0 3475);
DISPLAY INVISIBLE (0 3475);
FORCEPROP 1 LAST HDL_TAP TRUE
J 0
(325 3300);
DISPLAY 0.872340 (325 3300);
DISPLAY INVISIBLE (325 3300);
FORCEPROP 1 LAST PATH I99
J 0
(-2 3425);
DISPLAY 0.872340 (-2 3425);
PAINT GREEN (-2 3425);
DISPLAY INVISIBLE (-2 3425);
FORCEADD CAD_NOTE..1
(1850 -425);
FORCEPROP 0 LAST S1 PLACE THE BYPASS CAPS CLOSE TO DIMM
J 0
(1725 -550);
DISPLAY 1.021277 (1725 -550);
PAINT WHITE (1725 -550);
FORCEPROP 2 LAST CDS_LIB logical_power
J 0
(1850 -425);
PAINT MONO (1850 -425);
DISPLAY INVISIBLE (1850 -425);
FORCEPROP 1 LAST COMMENT_BODY TRUE
J 0
(1875 -325);
DISPLAY 0.978723 (1875 -325);
DISPLAY INVISIBLE (1875 -325);
FORCEADD QUANTA_TITLE_BLOCK_C..1
(6325 -1725);
FORCEPROP 0 LAST CDS_CON_LAST_MODIFIED Fri Aug 25 14:01:09 2023
J 0
(4440 -1710);
PAINT MONO (4440 -1710);
DISPLAY INVISIBLE (4440 -1710);
FORCEPROP 2 LAST CUSTOM_TXT_CDS <XR_PAGE_TITLE>
J 0
(-1565 3525);
DISPLAY 0.638298 (-1565 3525);
PAINT PINK (-1565 3525);
DISPLAY INVISIBLE (-1565 3525);
FORCEPROP 2 LAST CUSTOM_TXT_CDS <NAME_1>
J 0
(3150 -1550);
FORCEPROP 2 LAST CUSTOM_TXT_CDS <NAME_2>
J 0
(3150 -1675);
FORCEPROP 2 LAST CUSTOM_TXT_CDS <Q_PROJ>
J 0
(3943 -1623);
DISPLAY 1.212766 (3943 -1623);
FORCEPROP 2 LAST CUSTOM_TXT_CDS <Q_NUMBER>
J 0
(4922 -1622);
DISPLAY 1.212766 (4922 -1622);
FORCEPROP 2 LAST CUSTOM_TXT_CDS <Q_REV>
J 0
(6141 -1622);
DISPLAY 1.212766 (6141 -1622);
FORCEPROP 2 LAST CUSTOM_TXT_CDS <CON_PAGE_NUM> OF <CON_TOTAL_PAGES>
J 0
(5879 -1707);
DISPLAY 0.978723 (5879 -1707);
FORCEPROP 2 LAST CUSTOM_TXT_CDS <CON_LAST_MODIFIED>
J 0
(4440 -1710);
DISPLAY 0.978723 (4440 -1710);
FORCEPROP 1 LAST Q_TITLE DDR5 - CPU0 CHE DIMM1(YELLOW)
J 0
(-3041 -1699);
DISPLAY 2.446809 (-3041 -1699);
PAINT GREEN (-3041 -1699);
FORCEPROP 1 LAST Q_DEPT 
J 1
(2562 -1676);
DISPLAY 1.957447 (2562 -1676);
PAINT GREEN (2562 -1676);
FORCEPROP 1 LAST COMMENT_BODY TRUE
J 0
(6337 -1738);
DISPLAY 0.978723 (6337 -1738);
PAINT GREEN (6337 -1738);
DISPLAY INVISIBLE (6337 -1738);
FORCEPROP 2 LAST CDS_XR_PAGE_TITLE CR-90 : @S9S_MB_2U_LIB.S9S_MB_2U(SCH_1):PAGE90
J 0
(-1565 3525);
DISPLAY 0.638298 (-1565 3525);
PAINT PINK (-1565 3525);
DISPLAY INVISIBLE (-1565 3525);
FORCEPROP 2 LAST CDS_LIB pure_quanta
J 0
(6325 -1725);
PAINT MONO (6325 -1725);
DISPLAY INVISIBLE (6325 -1725);
FORCEPROP 1 LAST CDS_LMAN_SYM_OUTLINE -9475,6775,100,-125
J 0
(6325 -1725);
DISPLAY 0.468085 (6325 -1725);
PAINT GREEN (6325 -1725);
DISPLAY INVISIBLE (6325 -1725);
FORCEPROP 2 LAST PAGE_BORDER TRUE
J 0
(-1565 3525);
DISPLAY 0.638298 (-1565 3525);
PAINT PINK (-1565 3525);
DISPLAY INVISIBLE (-1565 3525);
WIRE 17 -1 (50 4050)(775 4050);
FORCEPROP 2 LAST SIG_NAME M_E_CPU0_SA_DQ<31:0>
J 0
(115 4060);
DISPLAY 0.680851 (115 4060);
PAINT WHITE (115 4060);
WIRE 17 -1 (-2525 2650)(-1700 2650);
FORCEPROP 2 LAST SIG_NAME M_E_CPU0_SA_CB<7:0>
J 0
(-2435 2660);
DISPLAY 0.680851 (-2435 2660);
PAINT WHITE (-2435 2660);
WIRE 17 -1 (-1700 2500)(-1700 2550);
WIRE 17 -1 (-1700 2450)(-1700 2500);
WIRE 17 -1 (-1700 2550)(-1700 2600);
WIRE 17 -1 (-1700 2600)(-1700 2650);
WIRE 17 -1 (-1700 2400)(-1700 2450);
WIRE 17 -1 (-1700 2350)(-1700 2400);
WIRE 17 -1 (-1700 2300)(-1700 2350);
WIRE 17 -1 (-2525 2200)(-1700 2200);
FORCEPROP 2 LAST SIG_NAME M_E_CPU0_SB_CB<7:0>
J 0
(-2435 2210);
DISPLAY 0.680851 (-2435 2210);
PAINT WHITE (-2435 2210);
WIRE 17 -1 (-1700 3750)(-1700 3800);
WIRE 17 -1 (-1700 3800)(-1700 3850);
WIRE 17 -1 (-1700 3850)(-1700 3900);
WIRE 17 -1 (-1700 3900)(-1700 3950);
WIRE 17 -1 (-1700 3950)(-1700 4000);
WIRE 17 -1 (-1700 4000)(-1700 4050);
WIRE 17 -1 (-2525 4050)(-1700 4050);
FORCEPROP 2 LAST SIG_NAME M_E_CPU0_SA_CA<6:0>
J 0
(-2435 4060);
DISPLAY 0.680851 (-2435 4060);
PAINT WHITE (-2435 4060);
WIRE 17 -1 (-1700 3350)(-1700 3400);
WIRE 17 -1 (-1700 3400)(-1700 3450);
WIRE 17 -1 (-1700 3450)(-1700 3500);
WIRE 17 -1 (-1700 3500)(-1700 3550);
WIRE 17 -1 (-1700 3550)(-1700 3600);
WIRE 17 -1 (-1700 3600)(-1700 3650);
WIRE 17 -1 (-2525 3650)(-1700 3650);
FORCEPROP 2 LAST SIG_NAME M_E_CPU0_SB_CA<6:0>
J 0
(-2435 3660);
DISPLAY 0.680851 (-2435 3660);
PAINT WHITE (-2435 3660);
WIRE 17 -1 (-1700 2050)(-1700 2100);
WIRE 17 -1 (-1700 2000)(-1700 2050);
WIRE 17 -1 (-1700 2100)(-1700 2150);
WIRE 17 -1 (-1700 2150)(-1700 2200);
WIRE 17 -1 (-1700 1950)(-1700 2000);
WIRE 17 -1 (-1700 1900)(-1700 1950);
WIRE 17 -1 (-1700 1850)(-1700 1900);
WIRE 17 -1 (50 4000)(50 4050);
WIRE 17 -1 (50 3950)(50 4000);
WIRE 17 -1 (50 3900)(50 3950);
WIRE 17 -1 (50 3850)(50 3900);
WIRE 17 -1 (50 3800)(50 3850);
WIRE 17 -1 (50 3750)(50 3800);
WIRE 17 -1 (50 3700)(50 3750);
WIRE 17 -1 (50 3650)(50 3700);
WIRE 17 -1 (50 3600)(50 3650);
WIRE 17 -1 (50 3550)(50 3600);
WIRE 17 -1 (50 3500)(50 3550);
WIRE 17 -1 (50 3450)(50 3500);
WIRE 17 -1 (50 3400)(50 3450);
WIRE 17 -1 (50 3350)(50 3400);
WIRE 17 -1 (50 3300)(50 3350);
WIRE 17 -1 (50 3250)(50 3300);
WIRE 17 -1 (50 3200)(50 3250);
WIRE 17 -1 (50 3150)(50 3200);
WIRE 17 -1 (50 3100)(50 3150);
WIRE 17 -1 (50 3050)(50 3100);
WIRE 17 -1 (50 3000)(50 3050);
WIRE 17 -1 (50 2950)(50 3000);
WIRE 17 -1 (50 2900)(50 2950);
WIRE 17 -1 (50 2850)(50 2900);
WIRE 17 -1 (50 2800)(50 2850);
WIRE 17 -1 (50 2750)(50 2800);
WIRE 17 -1 (50 2700)(50 2750);
WIRE 17 -1 (50 2650)(50 2700);
WIRE 17 -1 (50 2600)(50 2650);
WIRE 17 -1 (50 2550)(50 2600);
WIRE 17 -1 (50 2500)(50 2550);
WIRE 17 -1 (50 2400)(775 2400);
FORCEPROP 2 LAST SIG_NAME M_E_CPU0_SB_DQ<31:0>
J 0
(115 2410);
DISPLAY 0.680851 (115 2410);
PAINT WHITE (115 2410);
WIRE 17 -1 (50 2200)(50 2250);
WIRE 17 -1 (50 2150)(50 2200);
WIRE 17 -1 (50 2250)(50 2300);
WIRE 17 -1 (50 2300)(50 2350);
WIRE 17 -1 (50 2100)(50 2150);
WIRE 17 -1 (50 2050)(50 2100);
WIRE 17 -1 (50 2350)(50 2400);
WIRE 17 -1 (50 2000)(50 2050);
WIRE 17 -1 (50 1950)(50 2000);
WIRE 17 -1 (50 1900)(50 1950);
WIRE 17 -1 (50 1850)(50 1900);
WIRE 17 -1 (50 1800)(50 1850);
WIRE 17 -1 (50 1750)(50 1800);
WIRE 17 -1 (50 1700)(50 1750);
WIRE 17 -1 (50 1650)(50 1700);
WIRE 17 -1 (50 1600)(50 1650);
WIRE 17 -1 (50 1550)(50 1600);
WIRE 17 -1 (50 1500)(50 1550);
WIRE 17 -1 (50 1450)(50 1500);
WIRE 17 -1 (50 1400)(50 1450);
WIRE 17 -1 (50 1350)(50 1400);
WIRE 17 -1 (50 1300)(50 1350);
WIRE 17 -1 (50 1250)(50 1300);
WIRE 17 -1 (50 1200)(50 1250);
WIRE 17 -1 (50 1150)(50 1200);
WIRE 17 -1 (50 1100)(50 1150);
WIRE 17 -1 (50 1050)(50 1100);
WIRE 17 -1 (50 1000)(50 1050);
WIRE 17 -1 (50 950)(50 1000);
WIRE 17 -1 (50 900)(50 950);
WIRE 17 -1 (50 850)(50 900);
WIRE 17 -1 (2800 2100)(2800 2200);
WIRE 17 -1 (2800 2200)(2800 2300);
WIRE 17 -1 (2800 2300)(2800 2400);
WIRE 17 -1 (2800 2500)(2800 2400);
WIRE 17 -1 (2800 2500)(2800 2600);
WIRE 17 -1 (2800 2600)(2800 2700);
WIRE 17 -1 (2800 2700)(2800 2800);
WIRE 17 -1 (2800 2800)(2800 2900);
WIRE 17 -1 (2800 2900)(2800 3000);
WIRE 17 -1 (2800 3000)(3825 3000);
FORCEPROP 2 LAST SIG_NAME M_E_CPU0_SB_DQS_DP<9:0>
J 0
(3040 3010);
DISPLAY 0.680851 (3040 3010);
PAINT WHITE (3040 3010);
WIRE 17 -1 (2800 3150)(2800 3250);
WIRE 17 -1 (2800 3250)(2800 3350);
WIRE 17 -1 (2800 3350)(2800 3450);
WIRE 17 -1 (2800 3550)(2800 3450);
WIRE 17 -1 (2800 3550)(2800 3650);
WIRE 17 -1 (2800 3650)(2800 3750);
WIRE 17 -1 (2800 3750)(2800 3850);
WIRE 17 -1 (2800 3850)(2800 3950);
WIRE 17 -1 (2800 3950)(2800 4050);
WIRE 17 -1 (2800 4050)(3825 4050);
FORCEPROP 2 LAST SIG_NAME M_E_CPU0_SA_DQS_DP<9:0>
J 0
(3040 4060);
DISPLAY 0.680851 (3040 4060);
PAINT WHITE (3040 4060);
WIRE 17 -1 (2975 2050)(2975 2150);
WIRE 17 -1 (2975 2150)(2975 2250);
WIRE 17 -1 (2975 2250)(2975 2350);
WIRE 17 -1 (2975 2450)(2975 2350);
WIRE 17 -1 (2975 2450)(2975 2550);
WIRE 17 -1 (2975 2550)(2975 2650);
WIRE 17 -1 (2975 2650)(2975 2750);
WIRE 17 -1 (2975 2750)(2975 2850);
WIRE 17 -1 (2975 2850)(2975 2950);
WIRE 17 -1 (2975 2950)(3825 2950);
FORCEPROP 2 LAST SIG_NAME M_E_CPU0_SB_DQS_DN<9:0>
J 0
(3040 2960);
DISPLAY 0.680851 (3040 2960);
PAINT WHITE (3040 2960);
WIRE 17 -1 (2975 3100)(2975 3200);
WIRE 17 -1 (2975 3200)(2975 3300);
WIRE 17 -1 (2975 3300)(2975 3400);
WIRE 17 -1 (2975 3500)(2975 3400);
WIRE 17 -1 (2975 3500)(2975 3600);
WIRE 17 -1 (2975 3600)(2975 3700);
WIRE 17 -1 (2975 3700)(2975 3800);
WIRE 17 -1 (2975 3800)(2975 3900);
WIRE 17 -1 (2975 3900)(2975 4000);
WIRE 17 -1 (2975 4000)(3825 4000);
FORCEPROP 2 LAST SIG_NAME M_E_CPU0_SA_DQS_DN<9:0>
J 0
(3040 4010);
DISPLAY 0.680851 (3040 4010);
PAINT WHITE (3040 4010);
WIRE 16 -1 (-2475 1850)(-2475 1575);
WIRE 16 -1 (4425 4525)(4425 4025);
WIRE 16 -1 (2725 425)(2725 375);
WIRE 16 -1 (1725 250)(1725 425);
WIRE 16 -1 (6125 675)(6125 375);
WIRE 16 -1 (6125 725)(6125 675);
WIRE 16 -1 (5875 675)(6125 675);
WIRE 16 -1 (4425 375)(4425 775);
WIRE 16 -1 (3350 -175)(3350 -100);
WIRE 16 -1 (1725 50)(1725 -175);
WIRE 16 -1 (-1425 -300)(-1425 -225);
WIRE 16 -1 (-1425 775)(-2525 775);
FORCEPROP 2 LAST SIG_NAME TP_CHE_CPU0_DIMM1_FRU_0
J 0
(-2437 784);
DISPLAY 0.680851 (-2437 784);
PAINT WHITE (-2437 784);
WIRE 16 -1 (-1425 925)(-2525 925);
FORCEPROP 2 LAST SIG_NAME TP_CHE_CPU0_DIMM1_FRU_3
J 0
(-2437 934);
DISPLAY 0.680851 (-2437 934);
PAINT WHITE (-2437 934);
WIRE 16 -1 (-1425 975)(-2525 975);
FORCEPROP 2 LAST SIG_NAME TP_CHE_CPU0_DIMM1_FRU_4
J 0
(-2437 984);
DISPLAY 0.680851 (-2437 984);
PAINT WHITE (-2437 984);
WIRE 16 -1 (-1425 1025)(-2525 1025);
FORCEPROP 2 LAST SIG_NAME TP_CHE_CPU0_DIMM1_FRU_5
J 0
(-2437 1034);
DISPLAY 0.680851 (-2437 1034);
PAINT WHITE (-2437 1034);
WIRE 16 -1 (-1425 1075)(-2525 1075);
FORCEPROP 2 LAST SIG_NAME TP_CHE_CPU0_DIMM1_FRU_6
J 0
(-2437 1084);
DISPLAY 0.680851 (-2437 1084);
PAINT WHITE (-2437 1084);
WIRE 16 -1 (-1425 1175)(-2525 1175);
FORCEPROP 2 LAST SIG_NAME PWRGD_CHE_CPU0_DIMM1
J 0
(-2437 1184);
DISPLAY 0.680851 (-2437 1184);
PAINT WHITE (-2437 1184);
WIRE 16 -1 (-1325 1250)(-1375 1250);
WIRE 16 -1 (-1325 1325)(-2550 1325);
FORCEPROP 2 LAST SIG_NAME I3C_SPD_DDREFGH_CPU0_LVC1_SCL
J 0
(-2385 1335);
DISPLAY 0.680851 (-2385 1335);
PAINT WHITE (-2385 1335);
WIRE 16 -1 (-1325 1325)(-1325 1250);
WIRE 16 -1 (-2950 1325)(-2750 1325);
WIRE 16 -1 (-2950 1425)(-2950 1325);
WIRE 16 -1 (-1425 1425)(-2950 1425);
FORCEPROP 2 LAST SIG_NAME I3C_SPD_DDREFGH_CPU0_LVC1_SCL_R1
J 0
(-2485 1435);
DISPLAY 0.680851 (-2485 1435);
PAINT WHITE (-2485 1435);
WIRE 16 -1 (-1425 1525)(-2450 1525);
FORCEPROP 2 LAST SIG_NAME PD_CHE_CPU0_DIMM1_SAA
J 0
(-2485 1535);
DISPLAY 0.680851 (-2485 1535);
PAINT WHITE (-2485 1535);
WIRE 16 -1 (-2475 1575)(-1425 1575);
WIRE 16 -1 (-1425 1675)(-2525 1675);
FORCEPROP 2 LAST SIG_NAME M_E_CPU0_ALERT_N
J 0
(-2437 1684);
DISPLAY 0.680851 (-2437 1684);
PAINT WHITE (-2437 1684);
WIRE 16 -1 (-1425 875)(-2525 875);
FORCEPROP 2 LAST SIG_NAME TP_CHE_CPU0_DIMM1_FRU_2
J 0
(-2437 884);
DISPLAY 0.680851 (-2437 884);
PAINT WHITE (-2437 884);
WIRE 16 -1 (-1425 825)(-2525 825);
FORCEPROP 2 LAST SIG_NAME TP_CHE_CPU0_DIMM1_FRU_1
J 0
(-2437 834);
DISPLAY 0.680851 (-2437 834);
PAINT WHITE (-2437 834);
WIRE 16 -1 (-1425 1475)(-2450 1475);
FORCEPROP 2 LAST SIG_NAME I3C_SPD_DDREFGH_CPU0_LVC1_SDA
J 0
(-2485 1485);
DISPLAY 0.680851 (-2485 1485);
PAINT WHITE (-2485 1485);
WIRE 16 -1 (-1800 1775)(-2525 1775);
FORCEPROP 2 LAST SIG_NAME RST_M_EF_CPU0_FPGA_N
J 0
(-2437 1784);
DISPLAY 0.680851 (-2437 1784);
PAINT WHITE (-2437 1784);
WIRE 16 -1 (-1800 1775)(-1800 1725);
WIRE 16 -1 (-1800 1725)(-1425 1725);
WIRE 16 -1 (-1425 2725)(-2525 2725);
FORCEPROP 2 LAST SIG_NAME M_E_CPU0_CLK_DN<0>
J 0
(-2437 2734);
DISPLAY 0.680851 (-2437 2734);
PAINT WHITE (-2437 2734);
WIRE 16 -1 (-1425 3025)(-2525 3025);
FORCEPROP 2 LAST SIG_NAME M_E_CPU0_SA_CS_N<0>
J 0
(-2437 3034);
DISPLAY 0.680851 (-2437 3034);
PAINT WHITE (-2437 3034);
WIRE 16 -1 (-1425 2925)(-2525 2925);
FORCEPROP 2 LAST SIG_NAME M_E_CPU0_SB_CS_N<1>
J 0
(-2437 2934);
DISPLAY 0.680851 (-2437 2934);
PAINT WHITE (-2437 2934);
WIRE 16 -1 (-1425 2875)(-2525 2875);
FORCEPROP 2 LAST SIG_NAME M_E_CPU0_SB_CS_N<0>
J 0
(-2437 2884);
DISPLAY 0.680851 (-2437 2884);
PAINT WHITE (-2437 2884);
WIRE 16 -1 (-225 2275)(-50 2275);
WIRE 16 -1 (2600 3975)(2875 3975);
WIRE 16 -1 (2600 3875)(2875 3875);
WIRE 16 -1 (2600 3775)(2875 3775);
WIRE 16 -1 (2600 3675)(2875 3675);
WIRE 16 -1 (2600 3575)(2875 3575);
WIRE 16 -1 (2600 3475)(2875 3475);
WIRE 16 -1 (2600 3375)(2875 3375);
WIRE 16 -1 (2600 3275)(2875 3275);
WIRE 16 -1 (2600 3175)(2875 3175);
WIRE 16 -1 (2600 3075)(2875 3075);
WIRE 16 -1 (2600 2925)(2875 2925);
WIRE 16 -1 (2600 2825)(2875 2825);
WIRE 16 -1 (2600 2725)(2875 2725);
WIRE 16 -1 (2600 2625)(2875 2625);
WIRE 16 -1 (2600 2525)(2875 2525);
WIRE 16 -1 (2600 2425)(2875 2425);
WIRE 16 -1 (2600 2325)(2875 2325);
WIRE 16 -1 (2600 2225)(2875 2225);
WIRE 16 -1 (2600 2125)(2875 2125);
WIRE 16 -1 (2875 2025)(2600 2025);
WIRE 16 -1 (2600 4025)(2700 4025);
WIRE 16 -1 (2600 3925)(2700 3925);
WIRE 16 -1 (2600 3825)(2700 3825);
WIRE 16 -1 (2600 3725)(2700 3725);
WIRE 16 -1 (2600 3625)(2700 3625);
WIRE 16 -1 (2600 3525)(2700 3525);
WIRE 16 -1 (2600 3425)(2700 3425);
WIRE 16 -1 (2600 3325)(2700 3325);
WIRE 16 -1 (2600 3225)(2700 3225);
WIRE 16 -1 (2600 3125)(2700 3125);
WIRE 16 -1 (2600 2975)(2700 2975);
WIRE 16 -1 (2600 2875)(2700 2875);
WIRE 16 -1 (2600 2775)(2700 2775);
WIRE 16 -1 (2600 2675)(2700 2675);
WIRE 16 -1 (2600 2575)(2700 2575);
WIRE 16 -1 (2600 2475)(2700 2475);
WIRE 16 -1 (2600 2375)(2700 2375);
WIRE 16 -1 (2600 2275)(2700 2275);
WIRE 16 -1 (2600 2175)(2700 2175);
WIRE 16 -1 (2600 2075)(2700 2075);
WIRE 16 -1 (-225 3675)(-50 3675);
WIRE 16 -1 (-1600 3425)(-1425 3425);
WIRE 16 -1 (-1600 3375)(-1425 3375);
WIRE 16 -1 (-1425 3225)(-2525 3225);
FORCEPROP 2 LAST SIG_NAME M_E_CPU0_SA_PAR
J 0
(-2437 3234);
DISPLAY 0.680851 (-2437 3234);
PAINT WHITE (-2437 3234);
WIRE 16 -1 (4675 4025)(4425 4025);
WIRE 16 -1 (4425 4025)(4425 3975);
WIRE 16 -1 (4425 3975)(4675 3975);
WIRE 16 -1 (4425 3975)(4425 3925);
WIRE 16 -1 (4675 3925)(4425 3925);
WIRE 16 -1 (-225 3525)(-50 3525);
WIRE 16 -1 (-225 3475)(-50 3475);
WIRE 16 -1 (-225 2975)(-50 2975);
WIRE 16 -1 (-225 2675)(-50 2675);
WIRE 16 -1 (-225 2725)(-50 2725);
WIRE 16 -1 (-225 2925)(-50 2925);
WIRE 16 -1 (-225 2875)(-50 2875);
WIRE 16 -1 (-225 2775)(-50 2775);
WIRE 16 -1 (-225 2325)(-50 2325);
WIRE 16 -1 (-225 2225)(-50 2225);
WIRE 16 -1 (-1600 2275)(-1425 2275);
WIRE 16 -1 (-1600 2125)(-1425 2125);
WIRE 16 -1 (-1600 2075)(-1425 2075);
WIRE 16 -1 (-225 1825)(-50 1825);
WIRE 16 -1 (4675 3875)(4425 3875);
WIRE 16 -1 (4425 3825)(4425 3875);
WIRE 16 -1 (4425 3825)(4675 3825);
WIRE 16 -1 (4425 3775)(4425 3825);
WIRE 16 -1 (4675 3775)(4425 3775);
WIRE 16 -1 (4425 3725)(4425 3775);
WIRE 16 -1 (4425 3725)(4675 3725);
WIRE 16 -1 (4425 3675)(4425 3725);
WIRE 16 -1 (4425 3675)(4675 3675);
WIRE 16 -1 (4425 3625)(4425 3675);
WIRE 16 -1 (4425 3625)(4675 3625);
WIRE 16 -1 (4425 3575)(4425 3625);
WIRE 16 -1 (4425 3575)(4675 3575);
WIRE 16 -1 (4425 3525)(4425 3575);
WIRE 16 -1 (4425 3525)(4675 3525);
WIRE 16 -1 (4425 3475)(4425 3525);
WIRE 16 -1 (4425 3475)(4675 3475);
WIRE 16 -1 (4425 3425)(4425 3475);
WIRE 16 -1 (4425 3425)(4675 3425);
WIRE 16 -1 (4425 3375)(4425 3425);
WIRE 16 -1 (4425 3375)(4675 3375);
WIRE 16 -1 (4425 3325)(4425 3375);
WIRE 16 -1 (4425 3325)(4675 3325);
WIRE 16 -1 (4425 3275)(4425 3325);
WIRE 16 -1 (4675 3275)(4425 3275);
WIRE 16 -1 (4425 3225)(4425 3275);
WIRE 16 -1 (4425 3225)(4675 3225);
WIRE 16 -1 (4425 3175)(4425 3225);
WIRE 16 -1 (4425 3175)(4675 3175);
WIRE 16 -1 (4425 3125)(4425 3175);
WIRE 16 -1 (4425 3125)(4675 3125);
WIRE 16 -1 (4425 3075)(4425 3125);
WIRE 16 -1 (4425 3075)(4675 3075);
WIRE 16 -1 (4425 3025)(4675 3025);
WIRE 16 -1 (4425 3025)(4425 3075);
WIRE 16 -1 (4425 2975)(4425 3025);
WIRE 16 -1 (4425 2975)(4675 2975);
WIRE 16 -1 (4425 2925)(4425 2975);
WIRE 16 -1 (4425 2925)(4675 2925);
WIRE 16 -1 (4425 2875)(4425 2925);
WIRE 16 -1 (4425 2875)(4675 2875);
WIRE 16 -1 (4425 2825)(4425 2875);
WIRE 16 -1 (4425 2825)(4675 2825);
WIRE 16 -1 (4425 2775)(4425 2825);
WIRE 16 -1 (4675 2775)(4425 2775);
WIRE 16 -1 (4425 2725)(4425 2775);
WIRE 16 -1 (4425 2725)(4675 2725);
WIRE 16 -1 (4425 2675)(4425 2725);
WIRE 16 -1 (4425 2675)(4675 2675);
WIRE 16 -1 (4425 2625)(4425 2675);
WIRE 16 -1 (4425 2625)(4675 2625);
WIRE 16 -1 (4425 2575)(4425 2625);
WIRE 16 -1 (4425 2575)(4675 2575);
WIRE 16 -1 (4425 2525)(4425 2575);
WIRE 16 -1 (4425 2525)(4675 2525);
WIRE 16 -1 (4425 2475)(4425 2525);
WIRE 16 -1 (4425 2475)(4675 2475);
WIRE 16 -1 (4425 2425)(4425 2475);
WIRE 16 -1 (4425 2425)(4675 2425);
WIRE 16 -1 (4425 2375)(4425 2425);
WIRE 16 -1 (4425 2375)(4675 2375);
WIRE 16 -1 (4425 2325)(4425 2375);
WIRE 16 -1 (4425 2325)(4675 2325);
WIRE 16 -1 (4425 2275)(4425 2325);
WIRE 16 -1 (4675 2275)(4425 2275);
WIRE 16 -1 (4425 2225)(4425 2275);
WIRE 16 -1 (4425 2225)(4675 2225);
WIRE 16 -1 (4425 2175)(4425 2225);
WIRE 16 -1 (4425 2175)(4675 2175);
WIRE 16 -1 (4425 2125)(4425 2175);
WIRE 16 -1 (4425 2125)(4675 2125);
WIRE 16 -1 (4425 2075)(4425 2125);
WIRE 16 -1 (4425 2075)(4675 2075);
WIRE 16 -1 (4425 2025)(4675 2025);
WIRE 16 -1 (4425 2025)(4425 2075);
WIRE 16 -1 (4425 1975)(4425 2025);
WIRE 16 -1 (4425 1975)(4675 1975);
WIRE 16 -1 (4425 1925)(4425 1975);
WIRE 16 -1 (4425 1925)(4675 1925);
WIRE 16 -1 (4425 1875)(4425 1925);
WIRE 16 -1 (4425 1875)(4675 1875);
WIRE 16 -1 (4425 1825)(4425 1875);
WIRE 16 -1 (4425 1825)(4675 1825);
WIRE 16 -1 (4425 1775)(4425 1825);
WIRE 16 -1 (4675 1775)(4425 1775);
WIRE 16 -1 (4425 1725)(4425 1775);
WIRE 16 -1 (4425 1725)(4675 1725);
WIRE 16 -1 (4425 1675)(4425 1725);
WIRE 16 -1 (4425 1675)(4675 1675);
WIRE 16 -1 (4425 1625)(4425 1675);
WIRE 16 -1 (4425 1625)(4675 1625);
WIRE 16 -1 (4425 1575)(4425 1625);
WIRE 16 -1 (4425 1575)(4675 1575);
WIRE 16 -1 (4425 1525)(4425 1575);
WIRE 16 -1 (4425 1525)(4675 1525);
WIRE 16 -1 (4425 1475)(4425 1525);
WIRE 16 -1 (4425 1475)(4675 1475);
WIRE 16 -1 (4425 1425)(4425 1475);
WIRE 16 -1 (4425 1425)(4675 1425);
WIRE 16 -1 (4425 1375)(4425 1425);
WIRE 16 -1 (4425 1375)(4675 1375);
WIRE 16 -1 (4425 1325)(4425 1375);
WIRE 16 -1 (4425 1325)(4675 1325);
WIRE 16 -1 (4425 1275)(4425 1325);
WIRE 16 -1 (4675 1275)(4425 1275);
WIRE 16 -1 (4425 1225)(4425 1275);
WIRE 16 -1 (4425 1225)(4675 1225);
WIRE 16 -1 (4425 1175)(4425 1225);
WIRE 16 -1 (4425 1175)(4675 1175);
WIRE 16 -1 (4425 1125)(4425 1175);
WIRE 16 -1 (4425 1125)(4675 1125);
WIRE 16 -1 (4425 1075)(4425 1125);
WIRE 16 -1 (4425 1075)(4675 1075);
WIRE 16 -1 (4425 1025)(4425 1075);
WIRE 16 -1 (4425 1025)(4675 1025);
WIRE 16 -1 (4425 975)(4675 975);
WIRE 16 -1 (4425 975)(4425 1025);
WIRE 16 -1 (4425 925)(4425 975);
WIRE 16 -1 (4425 925)(4675 925);
WIRE 16 -1 (4425 875)(4425 925);
WIRE 16 -1 (4425 875)(4675 875);
WIRE 16 -1 (4425 825)(4425 875);
WIRE 16 -1 (4425 825)(4675 825);
WIRE 16 -1 (4425 775)(4425 825);
WIRE 16 -1 (4425 775)(4675 775);
WIRE 16 -1 (5875 4025)(6125 4025);
WIRE 16 -1 (5875 3975)(6125 3975);
WIRE 16 -1 (6125 4025)(6125 3975);
WIRE 16 -1 (5875 3925)(6125 3925);
WIRE 16 -1 (6125 3975)(6125 3925);
WIRE 16 -1 (5875 3875)(6125 3875);
WIRE 16 -1 (6125 3925)(6125 3875);
WIRE 16 -1 (5875 3825)(6125 3825);
WIRE 16 -1 (6125 3875)(6125 3825);
WIRE 16 -1 (5875 3775)(6125 3775);
WIRE 16 -1 (6125 3825)(6125 3775);
WIRE 16 -1 (5875 3725)(6125 3725);
WIRE 16 -1 (6125 3775)(6125 3725);
WIRE 16 -1 (5875 3675)(6125 3675);
WIRE 16 -1 (6125 3725)(6125 3675);
WIRE 16 -1 (5875 3625)(6125 3625);
WIRE 16 -1 (6125 3675)(6125 3625);
WIRE 16 -1 (5875 3575)(6125 3575);
WIRE 16 -1 (6125 3625)(6125 3575);
WIRE 16 -1 (5875 3525)(6125 3525);
WIRE 16 -1 (6125 3575)(6125 3525);
WIRE 16 -1 (5875 3475)(6125 3475);
WIRE 16 -1 (6125 3525)(6125 3475);
WIRE 16 -1 (5875 3425)(6125 3425);
WIRE 16 -1 (6125 3475)(6125 3425);
WIRE 16 -1 (5875 3375)(6125 3375);
WIRE 16 -1 (6125 3425)(6125 3375);
WIRE 16 -1 (5875 3325)(6125 3325);
WIRE 16 -1 (6125 3375)(6125 3325);
WIRE 16 -1 (5875 3275)(6125 3275);
WIRE 16 -1 (6125 3275)(6125 3325);
WIRE 16 -1 (5875 3225)(6125 3225);
WIRE 16 -1 (6125 3275)(6125 3225);
WIRE 16 -1 (6125 3175)(5875 3175);
WIRE 16 -1 (6125 3225)(6125 3175);
WIRE 16 -1 (6125 3125)(5875 3125);
WIRE 16 -1 (6125 3175)(6125 3125);
WIRE 16 -1 (5875 3075)(6125 3075);
WIRE 16 -1 (6125 3125)(6125 3075);
WIRE 16 -1 (5875 3025)(6125 3025);
WIRE 16 -1 (6125 3075)(6125 3025);
WIRE 16 -1 (5875 2975)(6125 2975);
WIRE 16 -1 (6125 3025)(6125 2975);
WIRE 16 -1 (5875 2925)(6125 2925);
WIRE 16 -1 (6125 2975)(6125 2925);
WIRE 16 -1 (5875 2875)(6125 2875);
WIRE 16 -1 (6125 2925)(6125 2875);
WIRE 16 -1 (5875 2825)(6125 2825);
WIRE 16 -1 (6125 2875)(6125 2825);
WIRE 16 -1 (5875 2775)(6125 2775);
WIRE 16 -1 (6125 2775)(6125 2825);
WIRE 16 -1 (5875 2725)(6125 2725);
WIRE 16 -1 (6125 2775)(6125 2725);
WIRE 16 -1 (6125 2675)(5875 2675);
WIRE 16 -1 (6125 2725)(6125 2675);
WIRE 16 -1 (6125 2625)(5875 2625);
WIRE 16 -1 (6125 2675)(6125 2625);
WIRE 16 -1 (5875 2575)(6125 2575);
WIRE 16 -1 (6125 2625)(6125 2575);
WIRE 16 -1 (5875 2525)(6125 2525);
WIRE 16 -1 (6125 2575)(6125 2525);
WIRE 16 -1 (5875 2475)(6125 2475);
WIRE 16 -1 (6125 2525)(6125 2475);
WIRE 16 -1 (5875 2425)(6125 2425);
WIRE 16 -1 (6125 2475)(6125 2425);
WIRE 16 -1 (5875 2375)(6125 2375);
WIRE 16 -1 (6125 2425)(6125 2375);
WIRE 16 -1 (5875 2325)(6125 2325);
WIRE 16 -1 (6125 2375)(6125 2325);
WIRE 16 -1 (5875 2275)(6125 2275);
WIRE 16 -1 (6125 2275)(6125 2325);
WIRE 16 -1 (5875 2225)(6125 2225);
WIRE 16 -1 (6125 2275)(6125 2225);
WIRE 16 -1 (6125 2175)(5875 2175);
WIRE 16 -1 (6125 2225)(6125 2175);
WIRE 16 -1 (6125 2125)(5875 2125);
WIRE 16 -1 (6125 2175)(6125 2125);
WIRE 16 -1 (5875 2075)(6125 2075);
WIRE 16 -1 (6125 2125)(6125 2075);
WIRE 16 -1 (5875 2025)(6125 2025);
WIRE 16 -1 (6125 2075)(6125 2025);
WIRE 16 -1 (5875 1975)(6125 1975);
WIRE 16 -1 (6125 2025)(6125 1975);
WIRE 16 -1 (5875 1925)(6125 1925);
WIRE 16 -1 (6125 1975)(6125 1925);
WIRE 16 -1 (5875 1875)(6125 1875);
WIRE 16 -1 (6125 1925)(6125 1875);
WIRE 16 -1 (5875 1825)(6125 1825);
WIRE 16 -1 (6125 1875)(6125 1825);
WIRE 16 -1 (5875 1775)(6125 1775);
WIRE 16 -1 (6125 1775)(6125 1825);
WIRE 16 -1 (5875 1725)(6125 1725);
WIRE 16 -1 (6125 1775)(6125 1725);
WIRE 16 -1 (6125 1675)(5875 1675);
WIRE 16 -1 (6125 1725)(6125 1675);
WIRE 16 -1 (6125 1625)(5875 1625);
WIRE 16 -1 (6125 1675)(6125 1625);
WIRE 16 -1 (6125 1575)(5875 1575);
WIRE 16 -1 (6125 1625)(6125 1575);
WIRE 16 -1 (6125 1525)(5875 1525);
WIRE 16 -1 (6125 1575)(6125 1525);
WIRE 16 -1 (5875 1475)(6125 1475);
WIRE 16 -1 (6125 1475)(6125 1525);
WIRE 16 -1 (6125 1425)(5875 1425);
WIRE 16 -1 (6125 1425)(6125 1475);
WIRE 16 -1 (6125 1375)(5875 1375);
WIRE 16 -1 (6125 1425)(6125 1375);
WIRE 16 -1 (6125 1325)(5875 1325);
WIRE 16 -1 (6125 1375)(6125 1325);
WIRE 16 -1 (5875 1275)(6125 1275);
WIRE 16 -1 (6125 1325)(6125 1275);
WIRE 16 -1 (5875 1225)(6125 1225);
WIRE 16 -1 (6125 1275)(6125 1225);
WIRE 16 -1 (5875 1175)(6125 1175);
WIRE 16 -1 (6125 1225)(6125 1175);
WIRE 16 -1 (5875 1125)(6125 1125);
WIRE 16 -1 (6125 1175)(6125 1125);
WIRE 16 -1 (5875 1075)(6125 1075);
WIRE 16 -1 (6125 1125)(6125 1075);
WIRE 16 -1 (5875 1025)(6125 1025);
WIRE 16 -1 (6125 1075)(6125 1025);
WIRE 16 -1 (5875 975)(6125 975);
WIRE 16 -1 (6125 1025)(6125 975);
WIRE 16 -1 (5875 925)(6125 925);
WIRE 16 -1 (6125 925)(6125 975);
WIRE 16 -1 (5875 875)(6125 875);
WIRE 16 -1 (6125 925)(6125 875);
WIRE 16 -1 (5875 775)(6125 775);
WIRE 16 -1 (6125 875)(6125 775);
WIRE 16 -1 (6125 775)(6125 725);
WIRE 16 -1 (5875 725)(6125 725);
WIRE 16 -1 (-225 1575)(-50 1575);
WIRE 16 -1 (-1425 3175)(-2525 3175);
FORCEPROP 2 LAST SIG_NAME M_E_CPU0_SB_PAR
J 0
(-2437 3184);
DISPLAY 0.680851 (-2437 3184);
PAINT WHITE (-2437 3184);
WIRE 16 -1 (-1425 575)(-2525 575);
FORCEPROP 2 LAST SIG_NAME M_E_CPU0_SB_RSP<0>
J 0
(-2437 584);
DISPLAY 0.680851 (-2437 584);
PAINT WHITE (-2437 584);
WIRE 16 -1 (-1425 625)(-2525 625);
FORCEPROP 2 LAST SIG_NAME M_E_CPU0_SA_RSP<0>
J 0
(-2437 634);
DISPLAY 0.680851 (-2437 634);
PAINT WHITE (-2437 634);
WIRE 16 -1 (-225 825)(-50 825);
WIRE 16 -1 (-225 875)(-50 875);
WIRE 16 -1 (-225 925)(-50 925);
WIRE 16 -1 (-225 975)(-50 975);
WIRE 16 -1 (-225 1025)(-50 1025);
WIRE 16 -1 (-225 1075)(-50 1075);
WIRE 16 -1 (-225 1125)(-50 1125);
WIRE 16 -1 (-225 1175)(-50 1175);
WIRE 16 -1 (-225 1225)(-50 1225);
WIRE 16 -1 (-225 1275)(-50 1275);
WIRE 16 -1 (-225 1325)(-50 1325);
WIRE 16 -1 (-225 1375)(-50 1375);
WIRE 16 -1 (-225 1425)(-50 1425);
WIRE 16 -1 (-225 1475)(-50 1475);
WIRE 16 -1 (-225 1525)(-50 1525);
WIRE 16 -1 (-225 1625)(-50 1625);
WIRE 16 -1 (-225 1675)(-50 1675);
WIRE 16 -1 (-225 1725)(-50 1725);
WIRE 16 -1 (-225 1775)(-50 1775);
WIRE 16 -1 (-225 1875)(-50 1875);
WIRE 16 -1 (-225 1925)(-50 1925);
WIRE 16 -1 (-225 1975)(-50 1975);
WIRE 16 -1 (-225 2025)(-50 2025);
WIRE 16 -1 (-225 2075)(-50 2075);
WIRE 16 -1 (-225 2125)(-50 2125);
WIRE 16 -1 (-225 2175)(-50 2175);
WIRE 16 -1 (-225 2375)(-50 2375);
WIRE 16 -1 (-225 2475)(-50 2475);
WIRE 16 -1 (-225 2525)(-50 2525);
WIRE 16 -1 (-225 2575)(-50 2575);
WIRE 16 -1 (-225 2625)(-50 2625);
WIRE 16 -1 (-225 2825)(-50 2825);
WIRE 16 -1 (-225 3025)(-50 3025);
WIRE 16 -1 (-225 3075)(-50 3075);
WIRE 16 -1 (-225 3125)(-50 3125);
WIRE 16 -1 (-225 3175)(-50 3175);
WIRE 16 -1 (-225 3225)(-50 3225);
WIRE 16 -1 (-225 3275)(-50 3275);
WIRE 16 -1 (-225 3325)(-50 3325);
WIRE 16 -1 (-225 3375)(-50 3375);
WIRE 16 -1 (-225 3425)(-50 3425);
WIRE 16 -1 (-225 3575)(-50 3575);
WIRE 16 -1 (-225 3625)(-50 3625);
WIRE 16 -1 (-225 3725)(-50 3725);
WIRE 16 -1 (-225 3775)(-50 3775);
WIRE 16 -1 (-225 3825)(-50 3825);
WIRE 16 -1 (-225 3875)(-50 3875);
WIRE 16 -1 (-225 3925)(-50 3925);
WIRE 16 -1 (-225 3975)(-50 3975);
WIRE 16 -1 (-1425 3075)(-2525 3075);
FORCEPROP 2 LAST SIG_NAME M_E_CPU0_SA_CS_N<1>
J 0
(-2437 3084);
DISPLAY 0.680851 (-2437 3084);
PAINT WHITE (-2437 3084);
WIRE 16 -1 (-1425 2775)(-2525 2775);
FORCEPROP 2 LAST SIG_NAME M_E_CPU0_CLK_DP<0>
J 0
(-2437 2784);
DISPLAY 0.680851 (-2437 2784);
PAINT WHITE (-2437 2784);
WIRE 16 -1 (-1600 1825)(-1425 1825);
WIRE 16 -1 (-1600 1875)(-1425 1875);
WIRE 16 -1 (-1600 1925)(-1425 1925);
WIRE 16 -1 (-1600 1975)(-1425 1975);
WIRE 16 -1 (-1600 2025)(-1425 2025);
WIRE 16 -1 (-1600 2375)(-1425 2375);
WIRE 16 -1 (-1600 2425)(-1425 2425);
WIRE 16 -1 (-1600 2525)(-1425 2525);
WIRE 16 -1 (-1600 2575)(-1425 2575);
WIRE 16 -1 (-1600 3625)(-1425 3625);
WIRE 16 -1 (-1600 4025)(-1425 4025);
WIRE 16 -1 (-1600 3575)(-1425 3575);
WIRE 16 -1 (-1600 3975)(-1425 3975);
WIRE 16 -1 (-1600 3525)(-1425 3525);
WIRE 16 -1 (-1600 3925)(-1425 3925);
WIRE 16 -1 (-1600 3475)(-1425 3475);
WIRE 16 -1 (-1600 3875)(-1425 3875);
WIRE 16 -1 (-1600 3825)(-1425 3825);
WIRE 16 -1 (-1600 3775)(-1425 3775);
WIRE 16 -1 (-1600 3325)(-1425 3325);
WIRE 16 -1 (-1600 3725)(-1425 3725);
WIRE 16 -1 (-1600 2175)(-1425 2175);
WIRE 16 -1 (-1600 2325)(-1425 2325);
WIRE 16 -1 (-1600 2475)(-1425 2475);
WIRE 16 -1 (-1600 2625)(-1425 2625);
WIRE 16 -1 (-225 4025)(-50 4025);
WIRE 16 -1 (-1425 75)(-2525 75);
FORCEPROP 2 LAST SIG_NAME PD_CHE_CPU0_DIMM1_SAA
J 0
(-2437 84);
DISPLAY 0.680851 (-2437 84);
PAINT WHITE (-2437 84);
WIRE 16 -1 (-1425 -25)(-1425 75);
WIRE 16 -1 (2725 375)(2725 250);
WIRE 16 -1 (3350 375)(2725 375);
WIRE 16 -1 (3350 250)(3350 375);
WIRE 16 -1 (3350 -100)(3350 50);
WIRE 16 -1 (3350 -100)(2725 -100);
WIRE 16 -1 (2725 -100)(2725 50);
WIRE 16 3135 (1375 650)(1375 -650);
WIRE 16 3135 (3975 650)(1375 650);
WIRE 16 3135 (1375 -650)(3975 -650);
WIRE 16 3135 (3975 -650)(3975 650);
DOT 1 (4425 1475);
DOT 1 (3350 -100);
DOT 1 (2725 375);
DOT 1 (4425 775);
DOT 1 (4425 875);
DOT 1 (4425 825);
DOT 1 (4425 975);
DOT 1 (4425 925);
DOT 1 (4425 1025);
DOT 1 (4425 1075);
DOT 1 (4425 1125);
DOT 1 (4425 1275);
DOT 1 (4425 1225);
DOT 1 (4425 1175);
DOT 1 (4425 1375);
DOT 1 (4425 1325);
DOT 1 (4425 1525);
DOT 1 (4425 1425);
DOT 1 (4425 1625);
DOT 1 (4425 1575);
DOT 1 (4425 1675);
DOT 1 (4425 1775);
DOT 1 (4425 1725);
DOT 1 (4425 1875);
DOT 1 (4425 1825);
DOT 1 (4425 1925);
DOT 1 (4425 2025);
DOT 1 (4425 1975);
DOT 1 (6125 875);
DOT 1 (6125 975);
DOT 1 (6125 925);
DOT 1 (6125 1025);
DOT 1 (6125 1075);
DOT 1 (6125 1125);
DOT 1 (6125 1175);
DOT 1 (6125 1225);
DOT 1 (6125 1275);
DOT 1 (6125 1325);
DOT 1 (6125 1375);
DOT 1 (6125 1425);
DOT 1 (6125 1475);
DOT 1 (6125 1525);
DOT 1 (6125 1625);
DOT 1 (6125 1575);
DOT 1 (6125 1675);
DOT 1 (6125 1725);
DOT 1 (6125 1775);
DOT 1 (6125 1825);
DOT 1 (6125 1875);
DOT 1 (6125 1925);
DOT 1 (6125 1975);
DOT 1 (6125 2025);
DOT 1 (4425 2075);
DOT 1 (4425 2125);
DOT 1 (4425 2175);
DOT 1 (4425 2225);
DOT 1 (4425 2275);
DOT 1 (4425 2325);
DOT 1 (4425 2375);
DOT 1 (4425 2425);
DOT 1 (4425 2475);
DOT 1 (4425 2525);
DOT 1 (4425 2675);
DOT 1 (4425 2575);
DOT 1 (4425 2625);
DOT 1 (4425 2775);
DOT 1 (4425 2725);
DOT 1 (4425 2825);
DOT 1 (4425 2875);
DOT 1 (4425 2925);
DOT 1 (4425 2975);
DOT 1 (4425 3025);
DOT 1 (4425 3075);
DOT 1 (4425 3125);
DOT 1 (4425 3175);
DOT 1 (4425 3325);
DOT 1 (4425 3225);
DOT 1 (4425 3275);
DOT 1 (4425 3425);
DOT 1 (4425 3375);
DOT 1 (4425 3575);
DOT 1 (4425 3475);
DOT 1 (4425 3525);
DOT 1 (4425 3625);
DOT 1 (4425 3675);
DOT 1 (4425 3725);
DOT 1 (4425 3825);
DOT 1 (4425 3775);
DOT 1 (4425 3975);
DOT 1 (4425 4025);
DOT 1 (6125 2075);
DOT 1 (6125 2125);
DOT 1 (6125 2175);
DOT 1 (6125 2225);
DOT 1 (6125 2275);
DOT 1 (6125 2325);
DOT 1 (6125 2375);
DOT 1 (6125 2425);
DOT 1 (6125 2475);
DOT 1 (6125 2525);
DOT 1 (6125 2575);
DOT 1 (6125 2625);
DOT 1 (6125 2675);
DOT 1 (6125 2725);
DOT 1 (6125 2775);
DOT 1 (6125 2825);
DOT 1 (6125 2875);
DOT 1 (6125 2925);
DOT 1 (6125 2975);
DOT 1 (6125 3025);
DOT 1 (6125 3075);
DOT 1 (6125 3125);
DOT 1 (6125 3175);
DOT 1 (6125 3225);
DOT 1 (6125 3275);
DOT 1 (6125 3325);
DOT 1 (6125 3375);
DOT 1 (6125 3425);
DOT 1 (6125 3475);
DOT 1 (6125 3525);
DOT 1 (6125 3575);
DOT 1 (6125 3675);
DOT 1 (6125 3625);
DOT 1 (6125 3725);
DOT 1 (6125 3775);
DOT 1 (6125 3825);
DOT 1 (6125 3875);
DOT 1 (6125 3925);
DOT 1 (6125 3975);
DOT 1 (6125 775);
DOT 1 (6125 725);
DOT 1 (6125 675);
FORCENOTE
20210728 MODIFY FOR GT
(-2925 4725) 0;
DISPLAY LEFT (-2925 4725);
DISPLAY 2.510638 (-2925 4725);
PAINT PINK (-2925 4725);
QUIT
